G04 ================== begin FILE IDENTIFICATION RECORD ==================*
G04 Layout Name:  t6m_pdb_d_0928_1400_274.brd*
G04 Film Name:    top.art*
G04 File Format:  Gerber RS274X*
G04 File Origin:  Cadence Allegro 16.3-S048*
G04 Origin Date:  Tue Nov 26 11:01:49 2013*
G04 *
G04 Layer:  DRAWING FORMAT/TITLE_BLOCK*
G04 Layer:  VIA CLASS/TOP*
G04 Layer:  PIN/TOP*
G04 Layer:  MANUFACTURING/PHOTOPLOT_OUTLINE*
G04 Layer:  ETCH/TOP*
G04 Layer:  DRAWING FORMAT/TITLE_DATA_TOP*
G04 *
G04 Offset:    (0.00 0.00)*
G04 Mirror:    No*
G04 Mode:      Positive*
G04 Rotation:  0*
G04 FullContactRelief:  No*
G04 UndefLineWidth:     6.00*
G04 ================== end FILE IDENTIFICATION RECORD ====================*
%FSLAX25Y25*MOIN*%
%IR0*IPPOS*OFA0.00000B0.00000*MIA0B0*SFA1.00000B1.00000*%
%ADD11C,.02*%
%ADD26C,.03*%
%ADD20C,.04*%
%ADD18C,.06*%
%ADD14C,.052*%
%ADD35C,.046*%
%ADD31C,.064*%
%ADD10C,.055*%
%ADD22R,.04X.04*%
%ADD28C,.039*%
%ADD16C,.093*%
%ADD19R,.06X.06*%
%ADD24C,.077*%
%ADD23R,.052X.052*%
%ADD21C,.095*%
%ADD34R,.046X.046*%
%ADD32R,.064X.064*%
%ADD13R,.055X.055*%
%ADD33C,.099*%
%ADD25R,.077X.077*%
%ADD38O,.205X.244*%
%ADD17R,.02X.018*%
%ADD29R,.018X.02*%
%ADD12C,.132*%
%ADD37C,.205*%
%ADD36R,.028X.032*%
%ADD39C,.315*%
%ADD15C,.126*%
%ADD30R,.022X.068*%
%ADD27C,.158*%
%ADD40C,.018*%
%ADD41C,.006*%
%ADD52C,.03004*%
%ADD53C,.05004*%
%ADD47C,.06204*%
%ADD66C,.05604*%
%ADD65C,.07404*%
%ADD45C,.06504*%
%ADD63C,.08704*%
%ADD50C,.10304*%
%ADD48C,.10504*%
%ADD51R,.06202X.06202*%
%ADD62R,.06202X.06204*%
%ADD42C,.63006*%
%ADD61C,.12806*%
%ADD57C,.13238*%
%ADD44C,.16406*%
%ADD67C,.198*%
%ADD60C,.13266*%
%ADD49R,.06502X.06502*%
%ADD54R,.05602X.05604*%
%ADD46R,.06502X.06504*%
%ADD43C,.15806*%
%ADD58C,.28353*%
%ADD55R,.05604X.05604*%
%ADD64R,.08704X.08702*%
%ADD56O,.28352X.32289*%
%ADD59C,.39377*%
G75*
%LPD*%
G75*
G36*
G01X90008Y24204D02*
X86552Y20748D01*
X49511D01*
G03X49481I-15J-1502D01*
G01X48307D01*
G02X48240Y21740I23J500D01*
G03X48882Y27996I-505J3213D01*
G03X45598Y22501I-1148J-3043D01*
G02X44941Y20748I-657J-753D01*
G01X40529D01*
G02X39872Y22501I0J1000D01*
G03X35598I-2137J2452D01*
G02X34941Y20748I-657J-753D01*
G01X30529D01*
G02X29872Y22501I0J1000D01*
G03X25598I-2137J2452D01*
G02X24941Y20748I-657J-753D01*
G01X20529D01*
G02X19872Y22501I0J1000D01*
G03X15598I-2137J2452D01*
G02X14941Y20748I-657J-753D01*
G01X5948D01*
G02X5000Y21604I-43J906D01*
G01Y53683D01*
G02X6731Y54364I1000J-1D01*
G03Y65542I6004J5589D01*
G02X5000Y66223I-731J682D01*
G01Y175706D01*
G02X6731Y176387I1000J-1D01*
G03Y187565I6004J5589D01*
G02X5000Y188246I-731J682D01*
G01Y262541D01*
G02X6731Y263222I1000J-1D01*
G03Y274400I6004J5589D01*
G02X5000Y275081I-731J682D01*
G01Y384564D01*
G02X6731Y385245I1000J-1D01*
G03Y396423I6004J5589D01*
G02X5000Y397104I-731J682D01*
G01Y522892D01*
X5495Y523388D01*
X5691Y523396D01*
G03Y533692I-200J5148D01*
G01X5495Y533700D01*
X5000Y534196D01*
Y595320D01*
X5078Y595398D01*
X5103D01*
X14109D01*
X17427D01*
G03Y604404I53J4503D01*
G01X14109D01*
X6946D01*
G02X6826Y604707I379J326D01*
G01Y622761D01*
X17427D01*
G03Y631767I53J4503D01*
G01X10908D01*
Y633164D01*
X11984Y634240D01*
X13590Y635847D01*
Y704027D01*
G02X14864Y704957I1000J-32D01*
G03X18024Y707717I683J2407D01*
G01X18007Y707835D01*
X18082Y708058D01*
X19014Y708990D01*
X26230D01*
X29498Y705722D01*
X78192D01*
X78241Y705771D01*
X93053D01*
X100105Y698719D01*
X105338D01*
G02X105838Y698219I0J-500D01*
G01Y446616D01*
X85948Y426726D01*
Y412181D01*
X89028Y409100D01*
Y389208D01*
X94053Y384184D01*
X94289D01*
G02X94996Y382476I0J-1000D01*
G01X91158Y378638D01*
Y369415D01*
X93871Y366702D01*
X106477D01*
X114067Y359112D01*
G02Y358404I-354J-354D01*
G01X111118Y355455D01*
Y89796D01*
G02X110618Y89296I-500J0D01*
G01X105693D01*
X99180Y82783D01*
Y74832D01*
X90024Y65676D01*
X90008Y65661D01*
Y24204D01*
G37*
G36*
G01X104331Y2004D02*
G02X100429Y5906I0J3902D01*
G01Y9843D01*
G03X92520Y17752I-7909J0D01*
G01X5906D01*
G02X2004Y21654I0J3902D01*
G01Y522387D01*
X3998D01*
Y21711D01*
G03X5905Y19745I1908J-58D01*
G01X5906D01*
Y19746D01*
X91602D01*
Y19745D01*
X92520D01*
G02X102422Y9843I-1J-9903D01*
G01Y5906D01*
G03X104330Y3997I1908J-1D01*
G01X104331D01*
Y3998D01*
X397638D01*
G03X401514Y7874I0J3876D01*
G01Y1915529D01*
X401515D01*
Y1915541D01*
X401514Y1915551D01*
Y2078740D01*
G03X397638Y2082616I-3876J0D01*
G01X104331D01*
Y2082617D01*
X104330D01*
G03X102422Y2080709I0J-1908D01*
G01Y2076772D01*
G02X99522Y2069769I-9903J-1D01*
G02X92520Y2066868I-7003J7002D01*
G01X5964D01*
G03X4556Y2066310I-59J-1907D01*
G03X3998Y2064961I1350J-1348D01*
G01Y1608989D01*
G02X3498Y1608489I-500J0D01*
G01X2504D01*
G02X2004Y1608989I0J500D01*
G01Y2064961D01*
G02X5905Y2068862I3901J0D01*
G01X92520D01*
G03X100429Y2076772I0J7909D01*
G01Y2080709D01*
G02X104331Y2084610I3902J-1D01*
G01X397638D01*
G02X403508Y2078740I0J-5870D01*
G01Y7874D01*
G02X397638Y2004I-5870J0D01*
G01X104331D01*
G37*
G36*
G01X6707Y637081D02*
G02X5000Y637788I-707J707D01*
G01Y716099D01*
G02X6477Y716977I1000J0D01*
G03X8027Y716698I1196J2198D01*
G02X8451Y716557I71J-495D01*
G01X9176Y715832D01*
Y639550D01*
X6707Y637081D01*
G37*
G36*
G01X83352Y777577D02*
Y726333D01*
X66753Y709734D01*
X32256D01*
X28668Y713322D01*
X15058D01*
X13486Y711750D01*
G02X11778Y712457I-708J707D01*
G01Y716910D01*
X10207Y718481D01*
X10133Y718704D01*
X10150Y718821D01*
G03X6477Y721373I-2477J354D01*
G02X5000Y722251I-477J878D01*
G01Y723973D01*
G02X6477Y724851I1000J0D01*
G03Y729247I1196J2198D01*
G02X5000Y730125I-477J878D01*
G01Y731847D01*
G02X6477Y732725I1000J0D01*
G03Y737121I1196J2198D01*
G02X5000Y737999I-477J878D01*
G01Y739721D01*
G02X6477Y740599I1000J0D01*
G03Y744995I1196J2198D01*
G02X5000Y745873I-477J878D01*
G01Y747595D01*
G02X6477Y748473I1000J0D01*
G03Y752869I1196J2198D01*
G02X5000Y753747I-477J878D01*
G01Y755469D01*
G02X6477Y756347I1000J0D01*
G03Y760743I1196J2198D01*
G02X5000Y761621I-477J878D01*
G01Y763343D01*
G02X6477Y764221I1000J0D01*
G03Y768617I1196J2198D01*
G02X5000Y769495I-477J878D01*
G01Y771217D01*
G02X6477Y772095I1000J0D01*
G03Y776491I1196J2198D01*
G02X5000Y777369I-477J878D01*
G01Y779091D01*
G02X6477Y779969I1000J0D01*
G03Y784365I1196J2198D01*
G02X5000Y785243I-477J878D01*
G01Y786965D01*
G02X6477Y787843I1000J0D01*
G03X8964Y792185I1196J2198D01*
G01X9002Y792222D01*
Y794061D01*
X10026Y795085D01*
X13528Y798587D01*
X27465D01*
X29286Y796766D01*
X31528Y794524D01*
X37832D01*
X52260Y780096D01*
X80833D01*
X83352Y777577D01*
G37*
G36*
G01X134977Y1824992D02*
X124955Y1814969D01*
G02X124601Y1814822I-354J353D01*
G01X123929D01*
G02X123101Y1816334I31J1000D01*
G03X123425Y1817038I-3182J1891D01*
G03X117094Y1820619I-3505J1190D01*
G03X116947Y1820434I2823J-2394D01*
G01X116879Y1820342D01*
X116472Y1820130D01*
X111710D01*
G02X110714Y1821215I0J1000D01*
G03X110719Y1821296I-1895J158D01*
G03X110720Y1821325I-1900J80D01*
G01Y1824470D01*
G03X106918I-1901J0D01*
G01Y1821378D01*
G03X106919Y1821311I1901J-5D01*
G03X106921Y1821256I1901J42D01*
G03X106925Y1821207I1897J130D01*
G02X105840Y1820122I-996J-89D01*
G03X105571Y1820127I-170J-1894D01*
G03X104619Y1819813I99J-1899D01*
G01X104493Y1819730D01*
X104267D01*
Y1819524D01*
X104163Y1819389D01*
G03X104136Y1819353I1507J-1159D01*
G03X103768Y1818228I1533J-1124D01*
G01Y1815227D01*
G03X104587Y1813664I1901J0D01*
G03X104803Y1813534I1087J1561D01*
G03X105832Y1813332I867J1693D01*
G02X106918Y1812380I87J-997D01*
G01Y1812118D01*
G03X106922Y1811981I1901J-13D01*
G03X106931Y1811889I1896J139D01*
G03X106936Y1811854I1885J251D01*
G01X106938Y1811838D01*
X106947Y1811780D01*
Y1811740D01*
G02X106469Y1811240I-500J0D01*
G01X99308D01*
X96520Y1808452D01*
X90982Y1802915D01*
Y1771927D01*
G03X90294Y1770014I2313J-1912D01*
G01Y1753568D01*
X109999Y1733863D01*
Y1497368D01*
X103135Y1490504D01*
Y1470053D01*
X88741Y1455659D01*
Y1428797D01*
X88754D01*
Y1398654D01*
X88735Y1398636D01*
Y1366456D01*
X83674Y1361395D01*
X48375D01*
X45714Y1364056D01*
Y1382826D01*
X34788Y1393752D01*
X27187D01*
X18782Y1402157D01*
Y1464614D01*
Y1467638D01*
G03X17443Y1476452I-1302J4311D01*
G01X14109D01*
X7312D01*
Y1494808D01*
X17427D01*
G03Y1503814I53J4503D01*
G01X5103D01*
X5000Y1503917D01*
Y1597497D01*
X5495Y1597993D01*
X5691Y1598001D01*
G03Y1608297I-200J5148D01*
G01X5495Y1608305D01*
X5000Y1608801D01*
Y1916021D01*
G02X6731Y1916702I1000J-1D01*
G03Y1927880I6004J5589D01*
G02X5000Y1928561I-731J682D01*
G01Y2020391D01*
G02X6731Y2021072I1000J-1D01*
G03Y2032250I6004J5589D01*
G02X5000Y2032931I-731J682D01*
G01Y2064961D01*
G02X5265Y2065602I906J1D01*
G02X5956Y2065866I641J-641D01*
G01X19941D01*
G02X20598Y2064113I0J-1000D01*
G03X24872I2137J-2452D01*
G02X25529Y2065866I657J753D01*
G01X29941D01*
G02X30598Y2064113I0J-1000D01*
G03X34872I2137J-2452D01*
G02X35529Y2065866I657J753D01*
G01X39941D01*
G02X40598Y2064113I0J-1000D01*
G03X44872I2137J-2452D01*
G02X45529Y2065866I657J753D01*
G01X49941D01*
G02X50598Y2064113I0J-1000D01*
G03X54872I2137J-2452D01*
G02X55529Y2065866I657J753D01*
G01X92520D01*
G03X98062Y2067380I-1J10905D01*
G03X99390Y2068304I-5547J9388D01*
G03X100230Y2069061I-6870J8468D01*
G03X101271Y2070266I-7709J7712D01*
G03X101911Y2071230I-8752J6505D01*
G03X103424Y2076772I-9392J5542D01*
G01Y2080709D01*
G02X104288Y2081614I907J-1D01*
G01X397638D01*
G02X400512Y2078740I0J-2874D01*
G01Y1352096D01*
X396136Y1347720D01*
Y675039D01*
X394560Y673463D01*
Y67593D01*
G02X392904Y66838I-1000J0D01*
G03Y57374I-4313J-4732D01*
G02X394560Y56619I656J-755D01*
G01Y33895D01*
X370217Y9552D01*
X113112D01*
X111151Y11513D01*
Y25370D01*
X112404Y26623D01*
G02X112757Y26770I354J-353D01*
G01X116269D01*
X116513Y26615D01*
X116575Y26484D01*
G03X123394Y29350I3345J1586D01*
G03X123137Y29903I-3474J-1278D01*
G01X123053Y30050D01*
X123098Y30384D01*
X124249Y31535D01*
Y56764D01*
X131998Y64513D01*
X138895D01*
X138959Y64496D01*
G03X139473Y64396I962J3575D01*
G03X141813Y64889I448J3675D01*
G01X161912D01*
X162035Y65012D01*
X163571D01*
X164799Y66240D01*
Y72963D01*
X160124Y77638D01*
Y83344D01*
G02X160265Y83692I500J0D01*
G03X158901Y86918I-1364J1325D01*
G01X158325D01*
G02X157921Y87018I33J1000D01*
G01Y89279D01*
G02X158327Y89380I439J-899D01*
G01X159417D01*
G03Y93182I0J1901D01*
G01X155370D01*
G03X154953Y93136I0J-1913D01*
G03X154942Y93134I334J-1870D01*
G01X154887Y93121D01*
X153299D01*
X150250Y90072D01*
X143296D01*
G02X142894Y90274I0J500D01*
G03X136544Y89591I-2975J-2203D01*
G01X136484Y89457D01*
X136236Y89296D01*
X123604D01*
X123356Y89457D01*
X123296Y89591D01*
G03X116544I-3376J-1520D01*
G01X116484Y89457D01*
X116236Y89296D01*
X115620D01*
G02X115120Y89796I0J500D01*
G01Y353590D01*
G02X115267Y353943I500J-1D01*
G01X118080Y356756D01*
X127045D01*
X132980Y362691D01*
Y421942D01*
X135138Y424100D01*
X136544D01*
G02X136946Y423898I0J-500D01*
G03X140465Y422440I2975J2204D01*
G01X140583Y422458D01*
X140807Y422384D01*
X144934Y418257D01*
G02X144581Y417404I-353J-353D01*
G01X143571D01*
X143327Y417559D01*
X143265Y417689D01*
G03Y414515I-3345J-1587D01*
G01X143327Y414645D01*
X143571Y414800D01*
X147128D01*
X148182Y413746D01*
X154819D01*
Y413646D01*
X157823D01*
Y413744D01*
X159754D01*
Y413643D01*
X162758D01*
Y416870D01*
G03X163258Y418194I-1501J1323D01*
G01Y420869D01*
G03X159256I-2001J0D01*
G01Y418773D01*
G02X158756Y418273I-500J0D01*
G02X158269Y418658I0J500D01*
G03X157923Y419398I-1948J-460D01*
G01X157823Y419531D01*
Y419600D01*
X157749D01*
G03X156321Y420200I-1429J-1402D01*
G01X148653D01*
X143638Y425215D01*
X143564Y425439D01*
X143582Y425557D01*
G03X136946Y428306I-3662J545D01*
G02X136544Y428104I-402J298D01*
G01X133480D01*
X128976Y423600D01*
Y364349D01*
X125387Y360760D01*
X118080D01*
X108135Y370704D01*
X105570D01*
G02X105070Y371204I0J500D01*
G01Y373411D01*
X104970D01*
Y375078D01*
X105070D01*
X105270Y375278D01*
X105898D01*
X106022Y375199D01*
G03X106344Y375042I815J1262D01*
G01X106452Y375004D01*
X106656Y374800D01*
X116269D01*
X116513Y374645D01*
X116575Y374515D01*
G03Y377689I3345J1587D01*
G01X116513Y377559D01*
X116269Y377404D01*
X108224D01*
G02X107877Y377544I0J500D01*
G03X106412Y377902I-1041J-1083D01*
G01X106343Y377882D01*
X105270D01*
X105070Y378082D01*
X104970D01*
Y379884D01*
X105070D01*
Y382888D01*
X103020D01*
G02X102520Y383388I0J500D01*
G01Y384233D01*
G02X103020Y384733I500J0D01*
G01X105070D01*
Y387737D01*
X104970D01*
Y389718D01*
X105070D01*
X105270Y389918D01*
X105949D01*
X106052Y389868D01*
G03X107364Y389867I657J1351D01*
G01X107467Y389918D01*
X114057D01*
G02X114410Y389771I-1J-500D01*
G01X116418Y387763D01*
X116482Y387481D01*
X116433Y387345D01*
G03X118677Y389589I3487J-1243D01*
G01X118541Y389540D01*
X118259Y389604D01*
X115342Y392520D01*
X107467D01*
X107364Y392571D01*
G03X106055I-655J-1352D01*
G01X105952Y392522D01*
X105270D01*
X105070Y392722D01*
X104970D01*
Y394522D01*
X105070D01*
Y397526D01*
X101851D01*
X101718Y397626D01*
G03X101254Y397885I-1199J-1603D01*
G01X101111Y397942D01*
X100938Y398196D01*
Y398350D01*
G02X101438Y398850I500J0D01*
G01X105346D01*
X105546Y399050D01*
X114647D01*
X118215Y402618D01*
X118499Y402680D01*
X118637Y402629D01*
G03X116419Y404900I1284J3472D01*
G01X116466Y404764D01*
X116401Y404486D01*
X113569Y401654D01*
X105546D01*
X105346Y401854D01*
X104765D01*
G02X104058Y403561I0J1000D01*
G01X105835Y405338D01*
X105943Y405376D01*
G03X104032Y407287I-492J1419D01*
G01X103994Y407179D01*
X99492Y402677D01*
Y401854D01*
X99392D01*
Y398526D01*
G02X98892Y398026I-500J0D01*
G01X97643D01*
G03X96565Y394337I0J-2002D01*
G02X96679Y392737I-538J-842D01*
G03X97985Y389218I1306J-1517D01*
G01X100218D01*
G02X100718Y388718I0J-500D01*
G01Y388528D01*
X100467Y388245D01*
X100278Y388222D01*
G03X100120Y388196I246J-1986D01*
G01X100071Y388186D01*
X95918D01*
G02X95565Y388333I1J500D01*
G01X93032Y390866D01*
Y410758D01*
X90097Y413693D01*
G02X89950Y414046I353J354D01*
G01Y425068D01*
X109840Y444958D01*
Y698219D01*
G02X110340Y698719I500J0D01*
G01X147542D01*
X155525Y706702D01*
Y715728D01*
X155580D01*
Y733681D01*
G02X155726Y734034I500J0D01*
G01X169216Y747523D01*
Y762731D01*
X172195Y765710D01*
Y771907D01*
X160884Y783218D01*
X158327D01*
X157802Y783743D01*
Y784831D01*
G02X157949Y785186I500J1D01*
G01X158142Y785378D01*
X159053D01*
G03X159231Y785387I-7J1902D01*
G01X159254Y785389D01*
X161094D01*
X162828Y787123D01*
Y789888D01*
X161270Y791446D01*
X151604D01*
X149924Y789766D01*
X143201D01*
G02X142503Y791482I0J1000D01*
G03X137337I-2583J2652D01*
G02X136639Y789766I-698J-716D01*
G01X130940D01*
X124954Y795752D01*
X121979Y798728D01*
X116802D01*
X113204Y802326D01*
Y874726D01*
X113947Y875469D01*
Y1024914D01*
X144082Y1055049D01*
Y1084806D01*
X175598Y1116322D01*
Y1123605D01*
X171606Y1127597D01*
X161323D01*
G02X160335Y1128751I0J1000D01*
G03X158456Y1130946I-1879J293D01*
G01X158340D01*
G02X157343Y1132024I0J1000D01*
G03X157217Y1132893I-1996J154D01*
G02X158151Y1134250I934J357D01*
G01X159382D01*
G03Y1138052I0J1901D01*
G01X155283D01*
X153977Y1136746D01*
X153762D01*
Y1136520D01*
X153679Y1136394D01*
G03X153366Y1135228I1585J-1050D01*
G02X152368Y1134166I-998J-62D01*
G01X143296D01*
G02X142894Y1134368I0J500D01*
G03X136319Y1133024I-2974J-2203D01*
G02X135833Y1132640I-486J116D01*
G01X124007D01*
G02X123521Y1133024I0J500D01*
G03X118088Y1135382I-3601J-859D01*
G02X116594Y1136251I-494J869D01*
G01Y1138079D01*
G02X118088Y1138948I1000J0D01*
G03Y1145382I1832J3217D01*
G02X116594Y1146251I-494J869D01*
G01Y1148079D01*
G02X118088Y1148948I1000J0D01*
G03Y1155382I1832J3217D01*
G02X116594Y1156251I-494J869D01*
G01Y1158079D01*
G02X118088Y1158948I1000J0D01*
G03Y1165382I1832J3217D01*
G02X116594Y1166251I-494J869D01*
G01Y1168079D01*
G02X118088Y1168948I1000J0D01*
G03Y1175382I1832J3217D01*
G02X116594Y1176251I-494J869D01*
G01Y1178079D01*
G02X118088Y1178948I1000J0D01*
G03Y1185382I1832J3217D01*
G02X116594Y1186251I-494J869D01*
G01Y1188079D01*
G02X118088Y1188948I1000J0D01*
G03Y1195382I1832J3217D01*
G02X116594Y1196251I-494J869D01*
G01Y1198079D01*
G02X118088Y1198948I1000J0D01*
G03Y1205382I1832J3217D01*
G02X116594Y1206251I-494J869D01*
G01Y1208079D01*
G02X118088Y1208948I1000J0D01*
G03Y1215382I1832J3217D01*
G02X116594Y1216251I-494J869D01*
G01Y1218079D01*
G02X118088Y1218948I1000J0D01*
G03X116352Y1223151I1832J3217D01*
G02X114681Y1222710I-964J266D01*
G01X110500Y1226891D01*
Y1339302D01*
X110565Y1339367D01*
Y1389154D01*
X110738Y1389327D01*
Y1394224D01*
X111999Y1395485D01*
X125305D01*
X134550Y1404730D01*
Y1432464D01*
X138650Y1436564D01*
X138904Y1436635D01*
X139031Y1436603D01*
G03X141930Y1437088I889J3594D01*
G01X150940D01*
X165858Y1452006D01*
Y1475607D01*
X162495Y1478970D01*
X159673D01*
G03X159216Y1479026I-458J-1846D01*
G01X158186D01*
X157909Y1479303D01*
Y1481142D01*
X158277Y1481510D01*
X160589D01*
X161499Y1482420D01*
Y1484556D01*
X160571Y1485484D01*
X138949D01*
X138702Y1485731D01*
G02Y1486439I353J354D01*
G01X138791Y1486528D01*
X139034Y1486600D01*
X139158Y1486574D01*
G03X136232Y1490523I762J3623D01*
G02X134529Y1489904I-996J88D01*
G01X123563Y1500870D01*
X123531Y1501011D01*
G03X120734Y1503808I-3611J-814D01*
G01X120593Y1503840D01*
X119627Y1504806D01*
G02X120246Y1506509I707J707D01*
G03X123622Y1510217I-326J3688D01*
G03X118182Y1513466I-3702J-20D01*
G03X117436Y1512942I1739J-3269D01*
G02X115765Y1513683I-671J741D01*
G01Y1516711D01*
G02X117436Y1517452I1000J0D01*
G03Y1522942I2484J2745D01*
G02X115765Y1523683I-671J741D01*
G01Y1526711D01*
G02X117436Y1527452I1000J0D01*
G03Y1532942I2484J2745D01*
G02X115765Y1533683I-671J741D01*
G01Y1536711D01*
G02X117436Y1537452I1000J0D01*
G03Y1542942I2484J2745D01*
G02X115765Y1543683I-671J741D01*
G01Y1546711D01*
G02X117436Y1547452I1000J0D01*
G03Y1552942I2484J2745D01*
G02X115765Y1553683I-671J741D01*
G01Y1556711D01*
G02X117436Y1557452I1000J0D01*
G03Y1562942I2484J2745D01*
G02X115765Y1563683I-671J741D01*
G01Y1566711D01*
G02X117436Y1567452I1000J0D01*
G03Y1572942I2484J2745D01*
G02X115765Y1573683I-671J741D01*
G01Y1576711D01*
G02X117436Y1577452I1000J0D01*
G03Y1582942I2484J2745D01*
G02X115765Y1583683I-671J741D01*
G01Y1586711D01*
G02X117436Y1587452I1000J0D01*
G03Y1592942I2484J2745D01*
G02X115765Y1593683I-671J741D01*
G01Y1596711D01*
G02X117436Y1597452I1000J0D01*
G03Y1602942I2484J2745D01*
G02X115765Y1603683I-671J741D01*
G01Y1736585D01*
X115750Y1736600D01*
Y1737012D01*
X125190Y1746452D01*
Y1798885D01*
X127219Y1800914D01*
X134576Y1808270D01*
G02X136254Y1807714I692J-722D01*
G03X136428Y1806999I3666J514D01*
G03X137034Y1805909I3492J1228D01*
G03X143207Y1806523I2886J2319D01*
G01X143269Y1806642D01*
X143716Y1806926D01*
X150348D01*
X156714Y1813292D01*
Y1813524D01*
G02X157214Y1814024I500J0D01*
G01X157361D01*
X157484Y1813945D01*
G03X157641Y1813854I1081J1684D01*
G03X158571Y1813630I920J1777D01*
G01X161005Y1813639D01*
X162981Y1813647D01*
X163011Y1813643D01*
G03X163478Y1813642I238J1988D01*
G03X164447Y1814027I-229J1988D01*
G03X165252Y1815631I-1196J1604D01*
G01Y1815650D01*
G03X164231Y1817395I-2002J0D01*
G03X163835Y1817564I-979J-1746D01*
G03X163242Y1817651I-584J-1914D01*
G01X160960Y1817642D01*
X160363Y1817640D01*
G02X159860Y1818140I-3J500D01*
G01Y1818545D01*
X159961Y1818646D01*
Y1821862D01*
X157810D01*
G02X157310Y1822362I0J500D01*
G01Y1822456D01*
X157258Y1822715D01*
X157326Y1822877D01*
G02X157787Y1823185I462J-192D01*
G01X159075D01*
G03X160722Y1824136I0J1902D01*
G03X159075Y1826988I-1647J950D01*
G01X158604D01*
G02X157650Y1828049I45J999D01*
G03X157657Y1828179I-1994J173D01*
G03X157647Y1828426I-2001J43D01*
G02X158647Y1829478I999J52D01*
G01X159822D01*
G03Y1833282I0J1902D01*
G01X155570D01*
G03X154285Y1832782I0J-1902D01*
G01X154068D01*
Y1832556D01*
X153985Y1832430D01*
G03X153669Y1831321I1585J-1051D01*
G03X153671Y1831281I1900J75D01*
G02X152672Y1830230I-998J-51D01*
G01X143296D01*
X142900Y1830429D01*
X142831Y1830517D01*
G03X136228Y1828501I-2911J-2288D01*
G03X136218Y1828191I3692J-274D01*
G03X136680Y1826437I3702J37D01*
G02X135784Y1824992I-896J-445D01*
G01X134977D01*
G37*
G36*
G01X65354Y795260D02*
G02I0J19700D01*
G37*
G36*
G01Y1145260D02*
G02I0J19700D01*
G37*
G36*
G01X86364Y1289755D02*
Y1260873D01*
X76681Y1251190D01*
X60105D01*
X59652Y1251643D01*
Y1254804D01*
X58812Y1255644D01*
X53839D01*
X53244Y1256239D01*
Y1260125D01*
Y1285444D01*
Y1290382D01*
X54504Y1291642D01*
X57356D01*
X57358Y1291640D01*
X60044D01*
X70206D01*
X84479D01*
X86364Y1289755D01*
G37*
%LPC*%
G75*
G36*
G01X10128Y562561D02*
G03X10375Y562992I-253J431D01*
G01X10376Y571210D01*
X10175Y571410D01*
Y574629D01*
X10075Y574762D01*
G02X9676Y575962I1602J1199D01*
G01Y578766D01*
G02X13678I2001J0D01*
G01Y575962D01*
G02X13279Y574762I-2001J-1D01*
G01X13179Y574629D01*
Y571410D01*
X12978Y571210D01*
Y563010D01*
G03X13231Y562576I500J1D01*
G02X10128Y562561I-1539J-2694D01*
G37*
G36*
G01X59747Y562568D02*
G03X59996Y563001I-251J432D01*
G01Y571964D01*
G03X59496Y572464I-500J0D01*
G01X59189D01*
X52796Y566072D01*
Y562867D01*
X52930Y562635D01*
X53046Y562568D01*
G02X49944I-1551J-2686D01*
G03X50193Y563001I-251J432D01*
G01X50194Y567150D01*
X57248Y574205D01*
Y575683D01*
X57148Y575816D01*
G02X56748Y577016I1602J1201D01*
G01Y579653D01*
G02X60752I2002J0D01*
G01Y577016D01*
G02X60352Y575816I-2002J1D01*
G01X60252Y575683D01*
Y574619D01*
G03X61959Y573912I1000J0D01*
G01X62318Y574271D01*
Y575749D01*
X62218Y575882D01*
G02X61818Y577082I1602J1201D01*
G01Y579654D01*
G02X65822I2002J0D01*
G01Y577082D01*
G02X65422Y575882I-2002J1D01*
G01X65322Y575749D01*
Y572530D01*
X64259D01*
X62600Y570871D01*
Y562867D01*
X62733Y562635D01*
X62849Y562568D01*
G02X59747I-1551J-2686D01*
G37*
G36*
G01X157357Y399788D02*
X157249Y399750D01*
X152299Y394800D01*
X143571D01*
X143327Y394645D01*
X143265Y394515D01*
G02Y397689I-3345J1587D01*
G01X143327Y397559D01*
X143571Y397404D01*
X151221D01*
X155408Y401591D01*
X155412Y401601D01*
Y402408D01*
G03X155265Y402761I-500J-1D01*
G01X153886Y404140D01*
Y407575D01*
G02X153938Y407958I1454J-2D01*
G01Y409077D01*
X157157D01*
X157290Y409177D01*
G02X158489Y409576I1199J-1602D01*
G01X161377D01*
G02Y405574I0J-2001D01*
G01X158490D01*
G02X157454Y405863I0J2001D01*
G03X156841Y405788I-259J-428D01*
G01X156794Y405741D01*
Y405344D01*
X158318Y403819D01*
Y401587D01*
G02X157357Y399788I-1453J-380D01*
G37*
G36*
G01X312560Y1989407D02*
Y1994087D01*
G02X316564I2002J0D01*
G01Y1989407D01*
G02X316483Y1988847I-2001J4D01*
G01X316464Y1988778D01*
Y1987306D01*
X312660D01*
Y1988778D01*
X312641Y1988847D01*
G02X312560Y1989407I1920J564D01*
G37*
G36*
G01X286964Y1863280D02*
Y1863064D01*
X286738D01*
X286613Y1862980D01*
G02X285562Y1862664I-1050J1585D01*
G01X279976D01*
G02Y1866466I0J1901D01*
G01X285562D01*
G02X286613Y1866150I1J-1901D01*
G01X286738Y1866066D01*
X286964D01*
Y1865850D01*
G02Y1863280I-1402J-1285D01*
G37*
G36*
G01X293606Y1856666D02*
X288794D01*
G02X287594Y1857066I1J2002D01*
G01X287461Y1857166D01*
X286820D01*
X286694Y1857083D01*
G02X285644Y1856766I-1051J1585D01*
G01X280240D01*
G02Y1860570I0J1902D01*
G01X285644D01*
G02X286694Y1860253I-1J-1902D01*
G01X286820Y1860170D01*
X287461D01*
X287594Y1860270D01*
G02X288794Y1860670I1201J-1602D01*
G01X293606D01*
G02Y1856666I0J-2002D01*
G37*
G36*
G01X279064Y1814871D02*
Y1819569D01*
G02X283068I2002J0D01*
G01Y1814871D01*
G02X282987Y1814311I-2001J4D01*
G01X282968Y1814242D01*
Y1812770D01*
X279164D01*
Y1814242D01*
X279145Y1814311D01*
G02X279064Y1814871I1920J564D01*
G37*
G36*
G01X143265Y1789815D02*
X143327Y1789685D01*
X143571Y1789530D01*
X145866D01*
X155150Y1798814D01*
Y1800063D01*
X155100Y1800166D01*
G02Y1801476I1352J655D01*
G01X155150Y1801579D01*
Y1804639D01*
X154388Y1805401D01*
Y1806238D01*
X154288D01*
Y1809242D01*
X157507D01*
X157640Y1809342D01*
G02X158840Y1809742I1201J-1602D01*
G01X162140D01*
G02Y1805738I0J-2002D01*
G01X158840D01*
G02X158782Y1805739I6J2002D01*
G03X157754Y1804740I-28J-999D01*
G01Y1801579D01*
X157804Y1801476D01*
G02Y1800166I-1352J-655D01*
G01X157754Y1800063D01*
Y1797736D01*
X146944Y1786926D01*
X143571D01*
X143327Y1786771D01*
X143265Y1786641D01*
G02Y1789815I-3345J1587D01*
G37*
G36*
G01X282084Y1640643D02*
Y1644883D01*
G02X286088I2002J0D01*
G01Y1640643D01*
G02X286007Y1640083I-2001J4D01*
G01X285988Y1640014D01*
Y1638542D01*
X282184D01*
Y1640014D01*
X282165Y1640083D01*
G02X282084Y1640643I1920J564D01*
G37*
G36*
G01X59978Y1562017D02*
Y1568703D01*
G03X59731Y1569134I-500J0D01*
G02X62834Y1569116I1567J2677D01*
G03X62582Y1568682I248J-434D01*
G01Y1560640D01*
X62682D01*
Y1557636D01*
X59463D01*
X59330Y1557536D01*
G02X58130Y1557136I-1201J1602D01*
G01X54108D01*
G02Y1561140I0J2002D01*
G01X58130D01*
G02X58696Y1561058I-1J-2002D01*
G03X59978Y1562017I282J959D01*
G37*
G36*
G01X9483Y1556491D02*
X9583Y1556624D01*
Y1559843D01*
X9784Y1560044D01*
Y1565240D01*
X10390Y1565847D01*
Y1568693D01*
G03X10142Y1569125I-500J0D01*
G01X10141D01*
G02X13243I1551J2686D01*
G01X13242D01*
G03X12994Y1568693I252J-432D01*
G01Y1564769D01*
X12533Y1564308D01*
G03X12386Y1563955I353J-354D01*
G01Y1560044D01*
X12587Y1559843D01*
Y1556624D01*
X12687Y1556491D01*
G02X13086Y1555291I-1602J-1199D01*
G01Y1552589D01*
G02X9084I-2001J0D01*
G01Y1555291D01*
G02X9483Y1556491I2001J1D01*
G37*
G36*
G01X20693Y1568815D02*
X20692D01*
G03X20210Y1568685I-128J-483D01*
G01X17786Y1566261D01*
Y1559911D01*
X17986Y1559711D01*
Y1556492D01*
X18086Y1556359D01*
G02X18486Y1555159I-1602J-1201D01*
G01Y1552159D01*
G02X14482I-2002J0D01*
G01Y1555159D01*
G02X14882Y1556359I2002J-1D01*
G01X14982Y1556492D01*
Y1559711D01*
X15182Y1559911D01*
Y1567339D01*
X18369Y1570526D01*
G03X18499Y1571008I-353J354D01*
G01Y1571009D01*
G02X20693Y1568815I2996J802D01*
G37*
G36*
G01X307158Y1523116D02*
Y1522900D01*
X306932D01*
X306807Y1522816D01*
G02X305756Y1522500I-1050J1585D01*
G01X302267D01*
G02Y1526302I0J1901D01*
G01X305756D01*
G02X306807Y1525986I1J-1901D01*
G01X306932Y1525902D01*
X307158D01*
Y1525686D01*
G02Y1523116I-1402J-1285D01*
G37*
G36*
G01X308636Y1515884D02*
X313894D01*
G02Y1511882I0J-2001D01*
G01X308636D01*
G02X307436Y1512281I-1J2001D01*
G01X307303Y1512381D01*
X306662D01*
X306536Y1512298D01*
G02X305486Y1511982I-1050J1585D01*
G01X301734D01*
G02Y1515784I0J1901D01*
G01X305486D01*
G02X306536Y1515468I0J-1901D01*
G01X306662Y1515385D01*
X307303D01*
X307436Y1515485D01*
G02X308635Y1515884I1199J-1602D01*
G01X308636D01*
G37*
G36*
G01X268232Y1463962D02*
Y1467760D01*
G02X272236I2002J0D01*
G01Y1463962D01*
G02X272155Y1463402I-2001J4D01*
G01X272136Y1463333D01*
Y1461860D01*
X268332D01*
Y1463333D01*
X268313Y1463402D01*
G02X268232Y1463962I1920J564D01*
G37*
G36*
G01X192933Y1383181D02*
G02X188171I-2381J-2215D01*
G03X188182Y1383194I-758J652D01*
G02X192922I2370J-2228D01*
G03X192933Y1383181I769J639D01*
G37*
G36*
G01X281806Y1290422D02*
Y1293959D01*
G02X285810I2002J0D01*
G01Y1290422D01*
G02X285729Y1289862I-2001J4D01*
G01X285710Y1289793D01*
Y1288320D01*
X281906D01*
Y1289793D01*
X281887Y1289862D01*
G02X281806Y1290422I1920J564D01*
G37*
G36*
G01X318516Y1171519D02*
Y1171302D01*
X318290D01*
X318165Y1171219D01*
G02X317114Y1170902I-1051J1584D01*
G01X312698D01*
G02Y1174706I0J1902D01*
G01X317114D01*
G02X318165Y1174389I0J-1901D01*
G01X318290Y1174306D01*
X318516D01*
Y1174089D01*
G02Y1171519I-1402J-1285D01*
G37*
G36*
G01X325796Y1160264D02*
X320208D01*
G02X319008Y1160664I1J2002D01*
G01X318875Y1160764D01*
X318234D01*
X318108Y1160681D01*
G02X317058Y1160364I-1051J1585D01*
G01X312527D01*
G02Y1164168I0J1902D01*
G01X317058D01*
G02X318108Y1163851I-1J-1902D01*
G01X318234Y1163768D01*
X318875D01*
X319008Y1163868D01*
G02X320208Y1164268I1201J-1602D01*
G01X325796D01*
G02Y1160264I0J-2002D01*
G37*
G36*
G01X280956Y1115751D02*
Y1119471D01*
G02X284960I2002J0D01*
G01Y1115751D01*
G02X284879Y1115191I-2001J4D01*
G01X284860Y1115122D01*
Y1113650D01*
X281056D01*
Y1115122D01*
X281037Y1115191D01*
G02X280956Y1115751I1920J564D01*
G37*
G36*
G01X180578Y1029337D02*
Y1029120D01*
X180353D01*
X180228Y1029037D01*
G02X179177Y1028720I-1051J1584D01*
G01X176974D01*
X176933Y1028714D01*
G02X175279Y1029245I-310J1876D01*
G01X174103Y1030421D01*
G02X176793Y1033111I1345J1345D01*
G01X177380Y1032524D01*
X179177D01*
G02X180228Y1032207I0J-1901D01*
G01X180353Y1032124D01*
X180578D01*
Y1031907D01*
G02Y1029337I-1401J-1285D01*
G37*
G36*
G01X182366Y1008428D02*
Y1008212D01*
X182141D01*
X182016Y1008128D01*
G02X180965Y1007812I-1050J1585D01*
G01X177676D01*
G03X177322Y1007665I0J-500D01*
G01X177043Y1007385D01*
G02X174353Y1010075I-1345J1345D01*
G01X175893Y1011614D01*
X180965D01*
G02X182016Y1011298I1J-1901D01*
G01X182141Y1011214D01*
X182366D01*
Y1010998D01*
G02Y1008428I-1401J-1285D01*
G37*
G36*
G01X173548Y997636D02*
Y997660D01*
G02X176944Y998835I1901J0D01*
G01X176962Y998812D01*
X177315Y998460D01*
X181203D01*
G02X181300Y998457I-10J-1902D01*
G03X182352Y999456I52J999D01*
G01Y1001556D01*
G02X186354I2001J0D01*
G01Y996558D01*
G02X185755Y995130I-2002J0D01*
G01Y995056D01*
X185686D01*
X185553Y994956D01*
G02X183153I-1200J1602D01*
G01X183020Y995056D01*
X182379D01*
X182253Y994973D01*
G02X181203Y994656I-1051J1585D01*
G01X175739D01*
X174104Y996291D01*
G02X173548Y997636I1346J1344D01*
G37*
G36*
G01X182648Y989673D02*
Y989456D01*
X182423D01*
X182298Y989373D01*
G02X181247Y989056I-1051J1584D01*
G01X177530D01*
X177087Y988613D01*
G02X174397Y991303I-1345J1345D01*
G01X175954Y992860D01*
X181247D01*
G02X182298Y992543I0J-1901D01*
G01X182423Y992460D01*
X182648D01*
Y992243D01*
G02Y989673I-1401J-1285D01*
G37*
G36*
G01X181579Y981053D02*
G03X182630Y982052I51J999D01*
G01Y983423D01*
G02X186634I2002J0D01*
G01Y979154D01*
G02X186034Y977726I-2002J1D01*
G01Y977652D01*
X185965D01*
X185832Y977552D01*
G02X183432I-1200J1602D01*
G01X183299Y977652D01*
X182658D01*
X182532Y977569D01*
G02X181482Y977252I-1051J1585D01*
G01X175361D01*
X173677Y978936D01*
G02X176367Y981626I1345J1345D01*
G01X176937Y981056D01*
X181482D01*
G02X181579Y981053I-10J-1902D01*
G37*
G36*
G01X182790Y972269D02*
Y972052D01*
X182565D01*
X182440Y971969D01*
G02X181389Y971652I-1051J1584D01*
G01X176987D01*
X176480Y971145D01*
G02X173790Y973835I-1345J1345D01*
G01X175411Y975456D01*
X181389D01*
G02X182440Y975139I0J-1901D01*
G01X182565Y975056D01*
X182790D01*
Y974839D01*
G02Y972269I-1401J-1285D01*
G37*
G36*
G01X181143Y964570D02*
G03X182194Y965569I51J999D01*
G01Y967371D01*
G02X186198I2002J0D01*
G01Y962671D01*
G02X185598Y961243I-2002J1D01*
G01Y961169D01*
X185529D01*
X185396Y961069D01*
G02X182996I-1200J1602D01*
G01X182863Y961169D01*
X182222D01*
X182096Y961086D01*
G02X181046Y960770I-1050J1585D01*
G01X175386D01*
X174014Y962141D01*
G02X176704Y964831I1345J1345D01*
G01X176815Y964719D01*
G03X177170Y964572I354J353D01*
G01X181046D01*
G02X181143Y964570I9J-1901D01*
G37*
G36*
G01X182536Y955786D02*
Y955570D01*
X182311D01*
X182186Y955486D01*
G02X181135Y955170I-1050J1585D01*
G01X177663D01*
G03X177309Y955023I0J-500D01*
G01X176906Y954619D01*
G02X174216Y957309I-1345J1345D01*
G01X175880Y958972D01*
X181135D01*
G02X182186Y958656I1J-1901D01*
G01X182311Y958572D01*
X182536D01*
Y958356D01*
G02Y955786I-1401J-1285D01*
G37*
G36*
G01X181231Y945478D02*
G03X182282Y946477I51J999D01*
G01Y948331D01*
G02X186286I2002J0D01*
G01Y943579D01*
G02X185686Y942151I-2002J1D01*
G01Y942077D01*
X185617D01*
X185484Y941977D01*
G02X183084I-1200J1602D01*
G01X182951Y942077D01*
X182310D01*
X182184Y941994D01*
G02X181134Y941678I-1050J1585D01*
G01X176159D01*
X174644Y943192D01*
G02X177334Y945882I1345J1345D01*
G01X177588Y945627D01*
G03X177942Y945480I354J353D01*
G01X181134D01*
G02X181231Y945478I9J-1901D01*
G37*
G36*
G01X273964Y940761D02*
Y944767D01*
G02X277968I2002J0D01*
G01Y940761D01*
G02X277887Y940201I-2001J4D01*
G01X277868Y940132D01*
Y938660D01*
X274064D01*
Y940132D01*
X274045Y940201D01*
G02X273964Y940761I1920J564D01*
G37*
G36*
G01X182624Y936694D02*
Y936478D01*
X182399D01*
X182274Y936394D01*
G02X181223Y936078I-1050J1585D01*
G01X178156D01*
G03X177803Y935931I1J-500D01*
G01X177356Y935484D01*
G02X174666Y938174I-1345J1345D01*
G01X176373Y939880D01*
X181223D01*
G02X182274Y939564I1J-1901D01*
G01X182399Y939480D01*
X182624D01*
Y939264D01*
G02Y936694I-1401J-1285D01*
G37*
G36*
G01X262426Y822319D02*
Y822102D01*
X262201D01*
X262076Y822019D01*
G02X260768Y821720I-1051J1585D01*
G01X260735Y821724D01*
X255837D01*
G02Y825528I0J1902D01*
G01X261791D01*
X262213Y825106D01*
X262426D01*
Y824889D01*
G02Y822319I-1401J-1285D01*
G37*
G36*
G01X260928Y810286D02*
X260895Y810290D01*
X255687D01*
G02Y814094I0J1902D01*
G01X261951D01*
X262225Y813819D01*
G03X262579Y813672I354J353D01*
G01X263159D01*
X263285Y813755D01*
G02X264335Y814072I1051J-1585D01*
G01X269780D01*
X269813Y814076D01*
G02X271415Y810847I257J-1884D01*
G01X270836Y810268D01*
X264335D01*
G02X263285Y810585I1J1902D01*
G01X263159Y810668D01*
X262361D01*
X262235Y810585D01*
G02X260928Y810286I-1050J1585D01*
G37*
G36*
G01X271112Y767036D02*
Y770968D01*
G02X275116I2002J0D01*
G01Y767036D01*
G02X275035Y766476I-2001J4D01*
G01X275016Y766407D01*
Y764934D01*
X271212D01*
Y766407D01*
X271193Y766476D01*
G02X271112Y767036I1920J564D01*
G37*
G36*
G01X283346Y591962D02*
Y595540D01*
G02X287350I2002J0D01*
G01Y591962D01*
G02X287269Y591402I-2001J4D01*
G01X287250Y591333D01*
Y589860D01*
X283446D01*
Y591333D01*
X283427Y591402D01*
G02X283346Y591962I1920J564D01*
G37*
G36*
G01X268793Y471778D02*
X265737D01*
G02Y475582I0J1902D01*
G01X269673D01*
X269929Y475325D01*
G03X270283Y475178I354J353D01*
G01X270290D01*
Y474962D01*
G02Y472392I-1402J-1285D01*
G01Y472176D01*
X270064D01*
X269939Y472092D01*
G02X268793Y471778I-1050J1585D01*
G37*
G36*
G01X268866Y461200D02*
X265722D01*
G02Y465004I0J1902D01*
G01X269746D01*
X270001Y464748D01*
G03X270355Y464601I354J353D01*
G01X270935D01*
X271061Y464684D01*
G02X272111Y465000I1050J-1585D01*
G01X274991D01*
G02Y461198I0J-1901D01*
G01X272111D01*
G02X271061Y461514I0J1901D01*
G01X270935Y461597D01*
X270137D01*
X270011Y461514D01*
G02X268866Y461200I-1050J1585D01*
G37*
G36*
G01X158807Y431068D02*
X155348D01*
G02X154187Y431463I-1J1901D01*
G01X154052Y431567D01*
X153846D01*
Y431793D01*
X153763Y431919D01*
G02X153453Y433121I1585J1050D01*
G03X152456Y434200I-997J79D01*
G01X143368D01*
G03X142957Y433986I-1J-500D01*
G02Y438218I-3037J2116D01*
G03X143368Y438004I410J286D01*
G01X152462D01*
G03X153457Y439095I-1J1000D01*
G02X153766Y440318I1894J172D01*
G01X153849Y440444D01*
Y440670D01*
X154055D01*
X154190Y440774D01*
G02X155351Y441170I1162J-1506D01*
G01X159019D01*
G02Y437366I0J-1902D01*
G01X158239D01*
G03X157243Y436281I0J-1000D01*
G02Y435956I-1895J-162D01*
G03X158239Y434870I996J-86D01*
G01X158807D01*
G02Y431068I0J-1901D01*
G37*
G36*
G01X279568Y417340D02*
Y421169D01*
G02X283570I2001J0D01*
G01Y417340D01*
G02X283490Y416780I-2000J0D01*
G01X283470Y416711D01*
Y415238D01*
X279668D01*
Y416711D01*
X279648Y416780D01*
G02X279568Y417340I1920J560D01*
G37*
G36*
G01X116575Y394515D02*
X116513Y394645D01*
X116269Y394800D01*
X115031D01*
X114956Y394777D01*
G02X115295Y397480I-458J1430D01*
G01X115417Y397404D01*
X116269D01*
X116513Y397559D01*
X116575Y397689D01*
G02Y394515I3345J-1587D01*
G37*
G36*
G01X269546Y241764D02*
Y245353D01*
G02X273548I2001J0D01*
G01Y241764D01*
G02X273468Y241204I-2000J0D01*
G01X273448Y241135D01*
Y239662D01*
X269646D01*
Y241135D01*
X269626Y241204D01*
G02X269546Y241764I1920J560D01*
G37*
G36*
G01X261535Y126326D02*
X258187D01*
X258139Y126374D01*
X256947D01*
G02Y130178I0J1902D01*
G01X259715D01*
X259763Y130130D01*
X261535D01*
G02X262586Y129813I0J-1901D01*
G01X262711Y129730D01*
X262936D01*
Y129513D01*
G02Y126943I-1401J-1285D01*
G01Y126726D01*
X262711D01*
X262586Y126643D01*
G02X261535Y126326I-1051J1584D01*
G37*
G36*
G01X261779Y113658D02*
X257125D01*
G02Y117460I0J1901D01*
G01X261779D01*
G02X262829Y117144I0J-1901D01*
G01X262955Y117061D01*
X263753D01*
X263879Y117144D01*
G02X264929Y117460I1050J-1585D01*
G01X267627D01*
G02Y113658I0J-1901D01*
G01X264929D01*
G02X263879Y113974I0J1901D01*
G01X263753Y114057D01*
X262955D01*
X262829Y113974D01*
G02X261779Y113658I-1050J1585D01*
G37*
G36*
G01X292482Y63718D02*
Y67732D01*
G02X296484I2001J0D01*
G01Y63718D01*
G02X296404Y63158I-2000J0D01*
G01X296384Y63089D01*
Y61616D01*
X292582D01*
Y63089D01*
X292562Y63158D01*
G02X292482Y63718I1920J560D01*
G37*
G36*
G01X156206Y52081D02*
X156256Y52184D01*
Y52687D01*
X155224Y53719D01*
Y55242D01*
X155124D01*
Y58246D01*
X158343D01*
X158476Y58346D01*
G02X159676Y58746I1201J-1602D01*
G01X162384D01*
G02Y54742I0J-2002D01*
G01X159676D01*
G02X159131Y54818I1J2002D01*
G01X159000Y54855D01*
X158738Y54787D01*
X158642Y54691D01*
G03Y53983I353J-354D01*
G01X158860Y53765D01*
Y52184D01*
X158910Y52081D01*
G02X158050Y50007I-1352J-655D01*
G01X157942Y49969D01*
X154741Y46768D01*
X143715D01*
G03X143264Y46483I0J-500D01*
G02X143265Y49657I-3344J1588D01*
G01X143327Y49527D01*
X143571Y49372D01*
X153663D01*
X156101Y51810D01*
X156139Y51918D01*
G02X156206Y52081I1420J-489D01*
G37*
G36*
G01X318745Y1985510D02*
X318604Y1985630D01*
X318544D01*
Y1985697D01*
X318444Y1985830D01*
G02X318044Y1987031I1601J1200D01*
G01Y1990215D01*
G02X321617Y1991454I2001J0D01*
G03X323202Y1991473I785J619D01*
G02X326804Y1990272I1601J-1201D01*
G01Y1987031D01*
G02X326404Y1985830I-2001J-1D01*
G01X326304Y1985697D01*
Y1985630D01*
X326244D01*
X326103Y1985510D01*
G02X323503I-1300J1521D01*
G01X323362Y1985630D01*
X323302D01*
Y1985697D01*
X323202Y1985830D01*
G02X322900Y1986412I1601J1200D01*
G03X321948I-476J-154D01*
G02X321646Y1985830I-1903J618D01*
G01X321546Y1985697D01*
Y1985630D01*
X321486D01*
X321345Y1985510D01*
G02X318745I-1300J1521D01*
G37*
G36*
G01X275299Y1911982D02*
G02X271816Y1913327I-1482J1345D01*
G01Y1916895D01*
G02X272216Y1918096I2001J1D01*
G01X272316Y1918229D01*
Y1918296D01*
X272376D01*
X272517Y1918416D01*
G02X275117I1300J-1521D01*
G01X275258Y1918296D01*
X275318D01*
Y1918229D01*
X275418Y1918096D01*
G02X275595Y1917814I-1601J-1201D01*
G03X276484I445J229D01*
G02X276661Y1918096I1778J-919D01*
G01X276760Y1918229D01*
Y1918296D01*
X276821D01*
X276962Y1918416D01*
G02X279562I1300J-1521D01*
G01X279703Y1918296D01*
X279764D01*
Y1918229D01*
X279863Y1918096D01*
G02X280044Y1917806I-1601J-1201D01*
G03X280935I446J227D01*
G02X281116Y1918096I1782J-911D01*
G01X281216Y1918229D01*
Y1918296D01*
X281276D01*
X281417Y1918416D01*
G02X284017I1300J-1521D01*
G01X284158Y1918296D01*
X284218D01*
Y1918229D01*
X284318Y1918096D01*
G02X284479Y1917845I-1600J-1203D01*
G03X285359I440J237D01*
G02X285520Y1918096I1761J-952D01*
G01X285620Y1918229D01*
Y1918296D01*
X285680D01*
X285821Y1918416D01*
G02X288421I1300J-1521D01*
G01X288562Y1918296D01*
X288622D01*
Y1918229D01*
X288722Y1918096D01*
G02X289122Y1916895I-1601J-1200D01*
G01Y1913327D01*
G02X285653Y1911967I-2001J0D01*
G03X284185I-734J-680D01*
G02X281232Y1911985I-1468J1360D01*
G03X279747I-743J-670D01*
G02X276780Y1911982I-1485J1342D01*
G03X275299I-741J-672D01*
G37*
G36*
G01X285323Y1810025D02*
X285182Y1810144D01*
X285122D01*
Y1810212D01*
X285022Y1810345D01*
G02X284622Y1811546I1601J1200D01*
G01Y1814400D01*
G02X288164Y1815678I2002J0D01*
G03X289805Y1815826I770J638D01*
G02X293552Y1814846I1745J-980D01*
G01Y1811546D01*
G02X293151Y1810345I-2002J1D01*
G01X293052Y1810212D01*
Y1810144D01*
X292991D01*
X292850Y1810025D01*
G02X290250I-1300J1521D01*
G01X290109Y1810144D01*
X290048D01*
Y1810212D01*
X289949Y1810345D01*
G02X289907Y1810403I1600J1203D01*
G03X288266I-821J-572D01*
G02X288224Y1810345I-1642J1145D01*
G01X288124Y1810212D01*
Y1810144D01*
X288064D01*
X287923Y1810025D01*
G02X285323I-1300J1521D01*
G37*
G36*
G01X272702Y1738196D02*
Y1741915D01*
G02X273103Y1743116I2002J-1D01*
G01X273202Y1743249D01*
Y1743316D01*
X273263D01*
X273404Y1743436D01*
G02X276004I1300J-1521D01*
G01X276145Y1743316D01*
X276206D01*
Y1743249D01*
X276305Y1743116D01*
G02X276371Y1743023I-1599J-1204D01*
G03X278036I832J554D01*
G02X278102Y1743116I1665J-1111D01*
G01X278202Y1743249D01*
Y1743316D01*
X278262D01*
X278403Y1743436D01*
G02X281003I1300J-1521D01*
G01X281144Y1743316D01*
X281204D01*
Y1743249D01*
X281304Y1743116D01*
G02X281330Y1743081I-1594J-1211D01*
G03X282956I813J582D01*
G02X282982Y1743116I1620J-1176D01*
G01X283082Y1743249D01*
Y1743316D01*
X283142D01*
X283283Y1743436D01*
G02X285883I1300J-1521D01*
G01X286024Y1743316D01*
X286084D01*
Y1743249D01*
X286184Y1743116D01*
G02X286222Y1743064I-1597J-1207D01*
G03X287860I819J574D01*
G02X287898Y1743116I1635J-1155D01*
G01X287998Y1743249D01*
Y1743316D01*
X288058D01*
X288199Y1743436D01*
G02X290799I1300J-1521D01*
G01X290940Y1743316D01*
X291000D01*
Y1743249D01*
X291100Y1743116D01*
G02X291500Y1741915I-1601J-1200D01*
G01Y1738735D01*
G02X287923Y1737502I-2001J0D01*
G03X286285Y1737412I-788J-617D01*
G02X282972Y1737277I-1702J1053D01*
G03X281346Y1737255I-805J-593D01*
G02X277705Y1738285I-1643J1143D01*
G01Y1738286D01*
G03X277206Y1738757I-499J-29D01*
G01X276998D01*
X276706Y1738465D01*
Y1738196D01*
G02X272702I-2002J0D01*
G37*
G36*
G01X288121Y1635797D02*
X287980Y1635916D01*
X287920D01*
Y1635984D01*
X287820Y1636117D01*
G02X287420Y1637318I1601J1200D01*
G01Y1641558D01*
G02X290978Y1642816I2001J0D01*
G03X292533I777J629D01*
G02X296092Y1641558I1557J-1258D01*
G01Y1637318D01*
G02X295691Y1636117I-2002J1D01*
G01X295592Y1635984D01*
Y1635916D01*
X295531D01*
X295390Y1635797D01*
G02X292790I-1300J1521D01*
G01X292649Y1635916D01*
X292588D01*
Y1635984D01*
X292489Y1636117D01*
G02X292222Y1636599I1601J1202D01*
G03X291289I-467J-180D01*
G02X291022Y1636117I-1868J720D01*
G01X290922Y1635984D01*
Y1635916D01*
X290862D01*
X290721Y1635797D01*
G02X288121I-1300J1521D01*
G37*
G36*
G01X286595Y1556933D02*
G02X283052Y1558211I-1541J1278D01*
G01Y1562451D01*
G02X283453Y1563652I2002J-1D01*
G01X283552Y1563785D01*
Y1563852D01*
X283613D01*
X283754Y1563972D01*
G02X286354I1300J-1521D01*
G01X286495Y1563852D01*
X286556D01*
Y1563785D01*
X286655Y1563652D01*
G02X286903Y1563218I-1600J-1202D01*
G03X287826I461J192D01*
G02X288074Y1563652I1848J-768D01*
G01X288174Y1563785D01*
Y1563852D01*
X288234D01*
X288375Y1563972D01*
G02X290975I1300J-1521D01*
G01X291116Y1563852D01*
X291176D01*
Y1563785D01*
X291276Y1563652D01*
G02X291562Y1563118I-1601J-1201D01*
G03X292505I472J167D01*
G02X292791Y1563652I1887J-667D01*
G01X292890Y1563785D01*
Y1563852D01*
X292951D01*
X293092Y1563972D01*
G02X295692I1300J-1521D01*
G01X295833Y1563852D01*
X295894D01*
Y1563785D01*
X295993Y1563652D01*
G02X296183Y1563344I-1601J-1200D01*
G03X297079I448J223D01*
G02X297269Y1563652I1791J-892D01*
G01X297368Y1563785D01*
Y1563852D01*
X297429D01*
X297570Y1563972D01*
G02X300170I1300J-1521D01*
G01X300311Y1563852D01*
X300372D01*
Y1563785D01*
X300471Y1563652D01*
G02X300872Y1562451I-1601J-1202D01*
G01Y1558211D01*
G02X297377Y1556878I-2002J0D01*
G03X295885I-746J-666D01*
G02X292819Y1556973I-1493J1333D01*
G03X291248I-786J-618D01*
G02X288134Y1556933I-1573J1238D01*
G03X286595I-770J-638D01*
G37*
G36*
G01X274221Y1459116D02*
X274080Y1459236D01*
X274020D01*
Y1459303D01*
X273920Y1459436D01*
G02X273520Y1460637I1601J1200D01*
G01Y1464435D01*
G02X277011Y1465771I2001J0D01*
G03X278500I744J668D01*
G02X281992Y1464435I1490J-1336D01*
G01Y1460637D01*
G02X281591Y1459436I-2002J1D01*
G01X281492Y1459303D01*
Y1459236D01*
X281431D01*
X281290Y1459116D01*
G02X278690I-1300J1521D01*
G01X278549Y1459236D01*
X278488D01*
Y1459303D01*
X278389Y1459436D01*
G02X278202Y1459737I1600J1203D01*
G03X277309I-447J-225D01*
G02X277122Y1459436I-1787J902D01*
G01X277022Y1459303D01*
Y1459236D01*
X276962D01*
X276821Y1459116D01*
G02X274221I-1300J1521D01*
G37*
G36*
G01X281093Y1388307D02*
G02X277978Y1388265I-1574J1236D01*
G03X276490Y1388322I-770J-638D01*
G02X273587Y1388351I-1438J1393D01*
G03X272097Y1388321I-732J-682D01*
G02X268578Y1389626I-1518J1305D01*
G01Y1393341D01*
G02X268978Y1394542I2001J1D01*
G01X269078Y1394675D01*
Y1394742D01*
X269138D01*
X269279Y1394862D01*
G02X271879I1300J-1521D01*
G01X272020Y1394742D01*
X272080D01*
Y1394675D01*
X272180Y1394542D01*
G02X272368Y1394238I-1601J-1200D01*
G03X273263I448J224D01*
G02X273451Y1394542I1789J-896D01*
G01X273550Y1394675D01*
Y1394742D01*
X273611D01*
X273752Y1394862D01*
G02X276352I1300J-1521D01*
G01X276493Y1394742D01*
X276554D01*
Y1394675D01*
X276653Y1394542D01*
G02X276839Y1394243I-1600J-1203D01*
G03X277731I446J225D01*
G02X277917Y1394542I1786J-904D01*
G01X278016Y1394675D01*
Y1394742D01*
X278077D01*
X278218Y1394862D01*
G02X280818I1300J-1521D01*
G01X280959Y1394742D01*
X281020D01*
Y1394675D01*
X281119Y1394542D01*
G02X281407Y1394003I-1601J-1202D01*
G03X282351I472J165D01*
G02X282639Y1394543I1889J-661D01*
G01X282738Y1394676D01*
Y1394744D01*
X282799D01*
X282940Y1394863D01*
G02X285540I1300J-1521D01*
G01X285681Y1394744D01*
X285742D01*
Y1394676D01*
X285841Y1394543D01*
G02X286242Y1393342I-1601J-1202D01*
G01Y1389544D01*
G02X282666Y1388308I-2002J0D01*
G03X281093Y1388307I-786J-618D01*
G37*
G36*
G01X287910Y1285576D02*
X287769Y1285696D01*
X287708D01*
Y1285763D01*
X287609Y1285896D01*
G02X287208Y1287097I1601J1202D01*
G01Y1290634D01*
G02X290851Y1291779I2001J0D01*
G03X292492I821J573D01*
G02X296134Y1290634I1641J-1145D01*
G01Y1287097D01*
G02X295734Y1285896I-2001J-1D01*
G01X295634Y1285763D01*
Y1285696D01*
X295574D01*
X295433Y1285576D01*
G02X292833I-1300J1521D01*
G01X292692Y1285696D01*
X292632D01*
Y1285763D01*
X292532Y1285896D01*
G02X292492Y1285952I1608J1191D01*
G03X290851I-820J-573D01*
G02X290811Y1285896I-1648J1135D01*
G01X290712Y1285763D01*
Y1285696D01*
X290651D01*
X290510Y1285576D01*
G02X287910I-1300J1521D01*
G37*
G36*
G01X281104Y1205505D02*
G02X277558Y1206777I-1545J1272D01*
G01Y1210314D01*
G02X277958Y1211515I2001J1D01*
G01X278058Y1211648D01*
Y1211716D01*
X278118D01*
X278259Y1211835D01*
G02X280859I1300J-1521D01*
G01X281000Y1211716D01*
X281060D01*
Y1211648D01*
X281160Y1211515D01*
G02X281413Y1211067I-1602J-1200D01*
G03X282340I463J189D01*
G02X282593Y1211515I1855J-752D01*
G01X282692Y1211648D01*
Y1211716D01*
X282753D01*
X282894Y1211835D01*
G02X285494I1300J-1521D01*
G01X285635Y1211716D01*
X285696D01*
Y1211648D01*
X285795Y1211515D01*
G02X285824Y1211476I-1592J-1214D01*
G03X287452I814J580D01*
G02X287481Y1211515I1621J-1175D01*
G01X287580Y1211648D01*
Y1211716D01*
X287641D01*
X287782Y1211835D01*
G02X290382I1300J-1521D01*
G01X290523Y1211716D01*
X290584D01*
Y1211648D01*
X290683Y1211515D01*
G02X290972Y1210972I-1601J-1201D01*
G03X291917I473J164D01*
G02X292206Y1211515I1890J-658D01*
G01X292306Y1211648D01*
Y1211716D01*
X292366D01*
X292507Y1211835D01*
G02X295107I1300J-1521D01*
G01X295248Y1211716D01*
X295308D01*
Y1211648D01*
X295408Y1211515D01*
G02X295808Y1210314I-1601J-1200D01*
G01Y1206777D01*
G02X292232Y1205542I-2001J0D01*
G03X290657I-787J-616D01*
G02X287452Y1205615I-1575J1235D01*
G03X285824I-814J-580D01*
G02X282649Y1205505I-1630J1162D01*
G03X281104I-772J-635D01*
G37*
G36*
G01X286888Y1110905D02*
X286747Y1111024D01*
X286686D01*
Y1111092D01*
X286587Y1111225D01*
G02X286186Y1112426I1601J1202D01*
G01Y1116146D01*
G02X289692Y1117467I2002J0D01*
G03X291194I751J660D01*
G02X294700Y1116146I1504J-1321D01*
G01Y1112426D01*
G02X294299Y1111225I-2002J1D01*
G01X294200Y1111092D01*
Y1111024D01*
X294139D01*
X293998Y1110905D01*
G02X291398I-1300J1521D01*
G01X291257Y1111024D01*
X291196D01*
Y1111092D01*
X291097Y1111225D01*
G02X290894Y1111560I1602J1200D01*
G03X289992I-451J-217D01*
G02X289789Y1111225I-1805J865D01*
G01X289690Y1111092D01*
Y1111024D01*
X289629D01*
X289488Y1110905D01*
G02X286888I-1300J1521D01*
G37*
G36*
G01X282638Y1029853D02*
G02X279122Y1031162I-1514J1309D01*
G01Y1034882D01*
G02X279523Y1036083I2002J-1D01*
G01X279622Y1036216D01*
Y1036284D01*
X279683D01*
X279824Y1036403D01*
G02X282424I1300J-1521D01*
G01X282565Y1036284D01*
X282626D01*
Y1036216D01*
X282725Y1036083D01*
G02X282941Y1035721I-1601J-1201D01*
G03X283849I454J210D01*
G02X284065Y1036083I1817J-839D01*
G01X284164Y1036216D01*
Y1036284D01*
X284225D01*
X284366Y1036403D01*
G02X286966I1300J-1521D01*
G01X287107Y1036284D01*
X287168D01*
Y1036216D01*
X287267Y1036083D01*
G02X287443Y1035804I-1599J-1204D01*
G03X288330I443J230D01*
G02X288506Y1036083I1775J-925D01*
G01X288606Y1036216D01*
Y1036284D01*
X288666D01*
X288807Y1036403D01*
G02X291407I1300J-1521D01*
G01X291548Y1036284D01*
X291608D01*
Y1036216D01*
X291708Y1036083D01*
G02X291911Y1035748I-1602J-1200D01*
G03X292813I451J217D01*
G02X293016Y1036083I1805J-865D01*
G01X293116Y1036216D01*
Y1036284D01*
X293176D01*
X293317Y1036403D01*
G02X295917I1300J-1521D01*
G01X296058Y1036284D01*
X296118D01*
Y1036216D01*
X296218Y1036083D01*
G02X296618Y1034882I-1601J-1200D01*
G01Y1031162D01*
G02X293113Y1029841I-2001J0D01*
G03X291611I-751J-660D01*
G02X288626Y1029815I-1504J1321D01*
G03X287147I-740J-673D01*
G02X284152Y1029853I-1481J1347D01*
G03X282638I-757J-654D01*
G37*
G36*
G01X182918Y1013711D02*
X182785Y1013811D01*
X182144D01*
X182018Y1013728D01*
G02X180968Y1013412I-1050J1585D01*
G01X175668D01*
X174128Y1014951D01*
G02X176818Y1017641I1345J1345D01*
G01X177097Y1017361D01*
G03X177451Y1017214I354J353D01*
G01X180968D01*
G02X181065Y1017212I9J-1901D01*
G03X182116Y1018211I51J999D01*
G01Y1019280D01*
G02X183318Y1021115I2002J0D01*
G03X183626Y1022739I-399J917D01*
G01X183344Y1023020D01*
X182329D01*
G02X181129Y1023420I1J2002D01*
G01X180996Y1023520D01*
X180355D01*
X180229Y1023437D01*
G02X179179Y1023120I-1051J1585D01*
G01X177710D01*
X177242Y1022652D01*
G02X174552Y1025342I-1345J1345D01*
G01X176134Y1026924D01*
X179179D01*
G02X180229Y1026607I-1J-1902D01*
G01X180355Y1026524D01*
X180996D01*
X181129Y1026624D01*
G02X182329Y1027024I1201J-1602D01*
G01X185002D01*
X189800Y1022225D01*
G02X187541Y1018995I-1415J-1415D01*
G03X186120Y1018088I-421J-907D01*
G01Y1015313D01*
G02X185520Y1013885I-2002J1D01*
G01Y1013811D01*
X185451D01*
X185318Y1013711D01*
G02X182918I-1200J1602D01*
G37*
G36*
G01X279894Y935915D02*
X279753Y936034D01*
X279692D01*
Y936102D01*
X279593Y936235D01*
G02X279192Y937436I1601J1202D01*
G01Y941442D01*
G02X282754Y942695I2001J0D01*
G03X284314I780J627D01*
G02X287876Y941442I1561J-1253D01*
G01Y937436D01*
G02X287475Y936235I-2002J1D01*
G01X287376Y936102D01*
Y936034D01*
X287315D01*
X287174Y935915D01*
G02X284574I-1300J1521D01*
G01X284433Y936034D01*
X284372D01*
Y936102D01*
X284273Y936235D01*
G02X284002Y936728I1601J1201D01*
G03X283066I-468J-176D01*
G02X282795Y936235I-1872J708D01*
G01X282696Y936102D01*
Y936034D01*
X282635D01*
X282494Y935915D01*
G02X279894I-1300J1521D01*
G37*
G36*
G01X282800Y860906D02*
G02X279696Y861047I-1495J1331D01*
G03X278157Y861131I-804J-595D01*
G02X275223Y861122I-1471J1357D01*
G03X273722Y861077I-731J-683D01*
G02X270180Y862354I-1541J1277D01*
G01Y866243D01*
G02X270580Y867444I2001J1D01*
G01X270680Y867577D01*
Y867644D01*
X270740D01*
X270881Y867764D01*
G02X273481I1300J-1521D01*
G01X273622Y867644D01*
X273682D01*
Y867577D01*
X273782Y867444D01*
G02X273983Y867114I-1601J-1201D01*
G03X274884I450J217D01*
G02X275085Y867444I1802J-871D01*
G01X275184Y867577D01*
Y867644D01*
X275245D01*
X275386Y867764D01*
G02X277986I1300J-1521D01*
G01X278127Y867644D01*
X278188D01*
Y867577D01*
X278287Y867444D01*
G02X278534Y867012I-1601J-1202D01*
G03X279457I461J192D01*
G02X279704Y867444I1848J-770D01*
G01X279804Y867577D01*
Y867644D01*
X279864D01*
X280005Y867764D01*
G02X282605I1300J-1521D01*
G01X282746Y867644D01*
X282806D01*
Y867577D01*
X282906Y867444D01*
G02X283098Y867132I-1601J-1201D01*
G03X283995I448J221D01*
G02X284187Y867444I1793J-889D01*
G01X284286Y867577D01*
Y867644D01*
X284347D01*
X284488Y867764D01*
G02X287088I1300J-1521D01*
G01X287229Y867644D01*
X287290D01*
Y867577D01*
X287389Y867444D01*
G02X287790Y866243I-1601J-1202D01*
G01Y862237D01*
G02X284293Y860906I-2002J0D01*
G03X282800I-746J-665D01*
G37*
G36*
G01X276884Y762190D02*
X276743Y762310D01*
X276682D01*
Y762377D01*
X276583Y762510D01*
G02X276182Y763711I1601J1202D01*
G01Y767643D01*
G02X279702Y768947I2002J0D01*
G03X281219I759J652D01*
G02X284738Y767643I1518J-1304D01*
G01Y763711D01*
G02X284338Y762510I-2001J-1D01*
G01X284238Y762377D01*
Y762310D01*
X284178D01*
X284037Y762190D01*
G02X281437I-1300J1521D01*
G01X281296Y762310D01*
X281236D01*
Y762377D01*
X281136Y762510D01*
G02X280916Y762881I1601J1200D01*
G03X280005I-455J-207D01*
G02X279785Y762510I-1821J829D01*
G01X279686Y762377D01*
Y762310D01*
X279625D01*
X279484Y762190D01*
G02X276884I-1300J1521D01*
G37*
G36*
G01X271578Y685832D02*
G02X268108Y687192I-1468J1360D01*
G01Y691124D01*
G02X268508Y692325I2001J1D01*
G01X268608Y692458D01*
Y692526D01*
X268668D01*
X268809Y692645D01*
G02X271409I1300J-1521D01*
G01X271550Y692526D01*
X271610D01*
Y692458D01*
X271710Y692325D01*
G02X271871Y692073I-1601J-1201D01*
G03X272752I440J237D01*
G02X272913Y692325I1762J-949D01*
G01X273012Y692458D01*
Y692526D01*
X273073D01*
X273214Y692645D01*
G02X275814I1300J-1521D01*
G01X275955Y692526D01*
X276016D01*
Y692458D01*
X276115Y692325D01*
G02X276291Y692046I-1599J-1204D01*
G03X277178I443J230D01*
G02X277354Y692325I1775J-925D01*
G01X277454Y692458D01*
Y692526D01*
X277514D01*
X277655Y692645D01*
G02X280255I1300J-1521D01*
G01X280396Y692526D01*
X280456D01*
Y692458D01*
X280556Y692325D01*
G02X280709Y692088I-1601J-1201D01*
G03X281586I439J240D01*
G02X281739Y692325I1754J-964D01*
G01X281838Y692458D01*
Y692526D01*
X281899D01*
X282040Y692645D01*
G02X284640I1300J-1521D01*
G01X284781Y692526D01*
X284842D01*
Y692458D01*
X284941Y692325D01*
G02X285342Y691124I-1601J-1202D01*
G01Y687192D01*
G02X281878Y685825I-2002J0D01*
G03X280417I-731J-683D01*
G02X277474Y685845I-1462J1367D01*
G03X275995I-740J-673D01*
G02X273045Y685832I-1481J1347D01*
G03X271578I-733J-679D01*
G37*
G36*
G01X289684Y587116D02*
X289543Y587236D01*
X289482D01*
Y587303D01*
X289383Y587436D01*
G02X288982Y588637I1601J1202D01*
G01Y592215D01*
G02X292493Y593530I2002J0D01*
G03X294000I754J657D01*
G02X297510Y592215I1509J-1315D01*
G01Y588637D01*
G02X297110Y587436I-2001J-1D01*
G01X297010Y587303D01*
Y587236D01*
X296950D01*
X296809Y587116D01*
G02X294209I-1300J1521D01*
G01X294068Y587236D01*
X294008D01*
Y587303D01*
X293908Y587436D01*
G02X293699Y587783I1601J1201D01*
G03X292794I-452J-213D01*
G02X292585Y587436I-1810J854D01*
G01X292486Y587303D01*
Y587236D01*
X292425D01*
X292284Y587116D01*
G02X289684I-1300J1521D01*
G37*
G36*
G01X270990Y510987D02*
G02X267514Y512341I-1474J1354D01*
G01Y515919D01*
G02X267915Y517120I2002J-1D01*
G01X268014Y517253D01*
Y517320D01*
X268075D01*
X268216Y517440D01*
G02X270816I1300J-1521D01*
G01X270957Y517320D01*
X271018D01*
Y517253D01*
X271117Y517120D01*
G02X271285Y516855I-1601J-1201D01*
G03X272169I442J234D01*
G02X272337Y517120I1769J-936D01*
G01X272436Y517253D01*
Y517320D01*
X272497D01*
X272638Y517440D01*
G02X275238I1300J-1521D01*
G01X275379Y517320D01*
X275440D01*
Y517253D01*
X275539Y517120D01*
G02X275725Y516820I-1601J-1201D01*
G03X276618I447J225D01*
G02X276804Y517120I1787J-901D01*
G01X276904Y517253D01*
Y517320D01*
X276964D01*
X277105Y517440D01*
G02X279705I1300J-1521D01*
G01X279846Y517320D01*
X279906D01*
Y517253D01*
X280006Y517120D01*
G02X280154Y516893I-1599J-1204D01*
G03X281027I436J243D01*
G02X281175Y517120I1747J-977D01*
G01X281274Y517253D01*
Y517320D01*
X281335D01*
X281476Y517440D01*
G02X284076I1300J-1521D01*
G01X284217Y517320D01*
X284278D01*
Y517253D01*
X284377Y517120D01*
G02X284778Y515919I-1601J-1202D01*
G01Y512341D01*
G02X281319Y510969I-2002J0D01*
G03X279862I-728J-685D01*
G02X276916Y511004I-1457J1372D01*
G03X275427I-744J-668D01*
G02X272464Y510987I-1489J1337D01*
G03X270990I-737J-676D01*
G37*
G36*
G01X116575Y414515D02*
X116513Y414645D01*
X116269Y414800D01*
X94318D01*
X92839Y416279D01*
X92731Y416317D01*
G02X92690Y419140I492J1419D01*
G03X93139Y420669I-355J935D01*
G02X94880Y420158I1208J893D01*
G03X94431Y418629I355J-935D01*
G02X94642Y418228I-1209J-892D01*
G01X94680Y418120D01*
X95396Y417404D01*
X108076D01*
G03X108783Y419111I0J1000D01*
G01X106342Y421552D01*
X106166D01*
Y421621D01*
X106090Y421804D01*
X105766Y422127D01*
Y422954D01*
G02X105774Y423125I1902J-3D01*
G03X104689Y424210I-996J89D01*
G02X104518Y424202I-174J1894D01*
G01X101990D01*
G02Y428006I0J1902D01*
G01X104518D01*
G02X104689Y427998I-3J-1902D01*
G03X105774Y429083I89J996D01*
G02X105766Y429254I1894J174D01*
G01Y433724D01*
X108130Y436088D01*
G02X110820Y433398I1345J-1345D01*
G01X109570Y432148D01*
Y429254D01*
G02X109567Y429157I-1902J10D01*
G03X110566Y428106I999J-51D01*
G01X113954D01*
X113956Y428104D01*
X116544D01*
G03X116946Y428306I0J500D01*
G02Y423898I2974J-2204D01*
G03X116544Y424100I-402J-298D01*
G01X115061D01*
X115046Y424086D01*
X112313D01*
X112296Y424102D01*
X111584D01*
G03X110877Y422395I0J-1000D01*
G01X112362Y420911D01*
G02X112759Y418804I-1345J-1344D01*
G03X113675Y417404I916J-400D01*
G01X116269D01*
X116513Y417559D01*
X116575Y417689D01*
G02Y414515I3345J-1587D01*
G37*
G36*
G01X285365Y412494D02*
X285224Y412614D01*
X285164D01*
Y412681D01*
X285064Y412814D01*
G02X284664Y414015I1601J1200D01*
G01Y417844D01*
G02X288111Y419228I2001J0D01*
G03X289556I723J691D01*
G02X293004Y417844I1446J-1384D01*
G01Y414015D01*
G02X292603Y412814I-2002J1D01*
G01X292504Y412681D01*
Y412614D01*
X292443D01*
X292302Y412494D01*
G02X289702I-1300J1521D01*
G01X289561Y412614D01*
X289500D01*
Y412681D01*
X289401Y412814D01*
G02X289267Y413017I1600J1202D01*
G03X288400I-434J-249D01*
G02X288266Y412814I-1734J999D01*
G01X288166Y412681D01*
Y412614D01*
X288106D01*
X287965Y412494D01*
G02X285365I-1300J1521D01*
G37*
G36*
G01X282554Y336341D02*
G02X279072Y337688I-1480J1347D01*
G01Y341517D01*
G02X279473Y342718I2002J-1D01*
G01X279572Y342851D01*
Y342918D01*
X279633D01*
X279774Y343038D01*
G02X282374I1300J-1521D01*
G01X282515Y342918D01*
X282576D01*
Y342851D01*
X282675Y342718D01*
G02X282850Y342440I-1601J-1202D01*
G03X283737I443J231D01*
G02X283912Y342718I1776J-924D01*
G01X284012Y342851D01*
Y342918D01*
X284072D01*
X284213Y343038D01*
G02X286813I1300J-1521D01*
G01X286954Y342918D01*
X287014D01*
Y342851D01*
X287114Y342718D01*
G02X287266Y342483I-1600J-1202D01*
G03X288142I438J241D01*
G02X288294Y342718I1752J-967D01*
G01X288394Y342851D01*
Y342918D01*
X288454D01*
X288595Y343038D01*
G02X291195I1300J-1521D01*
G01X291336Y342918D01*
X291396D01*
Y342851D01*
X291496Y342718D01*
G02X291740Y342294I-1600J-1203D01*
G03X292661I460J194D01*
G02X292905Y342718I1844J-779D01*
G01X293004Y342851D01*
Y342918D01*
X293065D01*
X293206Y343038D01*
G02X295806I1300J-1521D01*
G01X295947Y342918D01*
X296008D01*
Y342851D01*
X296107Y342718D01*
G02X296508Y341517I-1601J-1202D01*
G01Y337688D01*
G02X292969Y336406I-2002J0D01*
G03X291432I-768J-640D01*
G02X288434Y336320I-1537J1282D01*
G03X286974I-730J-683D01*
G02X284033Y336341I-1461J1368D01*
G03X282554I-739J-674D01*
G37*
G36*
G01X275317Y236918D02*
X275176Y237038D01*
X275116D01*
Y237105D01*
X275016Y237238D01*
G02X274616Y238439I1601J1200D01*
G01Y241400D01*
G02X278079Y242766I2001J0D01*
G03X279604Y242841I731J683D01*
G02X283194Y241624I1589J-1217D01*
G01Y238439D01*
G02X282794Y237238I-2001J-1D01*
G01X282694Y237105D01*
Y237038D01*
X282634D01*
X282493Y236918D01*
G02X279893I-1300J1521D01*
G01X279752Y237038D01*
X279692D01*
Y237105D01*
X279592Y237238D01*
G02X279362Y237630I1600J1202D01*
G03X278448I-457J-202D01*
G02X278218Y237238I-1830J810D01*
G01X278118Y237105D01*
Y237038D01*
X278058D01*
X277917Y236918D01*
G02X275317I-1300J1521D01*
G37*
G36*
G01X288954Y161255D02*
G02X285932Y161202I-1534J1285D01*
G03X284488Y161247I-744J-669D01*
G02X281084Y162675I-1402J1428D01*
G01Y166264D01*
G02X281485Y167465I2002J-1D01*
G01X281584Y167598D01*
Y167666D01*
X281645D01*
X281786Y167785D01*
G02X284386I1300J-1521D01*
G01X284527Y167666D01*
X284588D01*
Y167598D01*
X284687Y167465D01*
G02X284820Y167264I-1600J-1203D01*
G03X285686I433J250D01*
G02X285819Y167465I1733J-1002D01*
G01X285918Y167598D01*
Y167666D01*
X285979D01*
X286120Y167785D01*
G02X288720I1300J-1521D01*
G01X288861Y167666D01*
X288922D01*
Y167598D01*
X289021Y167465D01*
G02X289229Y167119I-1602J-1199D01*
G03X290134I453J214D01*
G02X290342Y167465I1810J-853D01*
G01X290442Y167598D01*
Y167666D01*
X290502D01*
X290643Y167785D01*
G02X293243I1300J-1521D01*
G01X293384Y167666D01*
X293444D01*
Y167598D01*
X293544Y167465D01*
G02X293775Y167069I-1602J-1200D01*
G03X294691I458J202D01*
G02X294922Y167465I1833J-804D01*
G01X295022Y167598D01*
Y167666D01*
X295082D01*
X295223Y167785D01*
G02X297823I1300J-1521D01*
G01X297964Y167666D01*
X298024D01*
Y167598D01*
X298124Y167465D01*
G02X298524Y166264I-1601J-1200D01*
G01Y162585D01*
G02X294983Y161306I-2001J0D01*
G03X293457Y161321I-769J-639D01*
G02X290461Y161285I-1514J1309D01*
G03X288954Y161255I-740J-672D01*
G37*
G36*
G01X298387Y58872D02*
X298246Y58992D01*
X298186D01*
Y59059D01*
X298086Y59192D01*
G02X297686Y60393I1601J1200D01*
G01Y63778D01*
G02X301175Y65116I2001J0D01*
G03X302663I744J669D01*
G02X305651Y65103I1488J-1338D01*
G03X307151I750J662D01*
G02X310131Y65126I1500J-1325D01*
G03X311609I739J673D01*
G02X314582Y65111I1480J-1348D01*
G03X316074I746J666D01*
G02X319047Y65126I1493J-1333D01*
G03X320525I739J673D01*
G02X324006Y63778I1479J-1348D01*
G01Y60393D01*
G02X323606Y59192I-2001J-1D01*
G01X323506Y59059D01*
Y58992D01*
X323446D01*
X323305Y58872D01*
G02X320705I-1300J1521D01*
G01X320564Y58992D01*
X320504D01*
Y59059D01*
X320404Y59192D01*
G02X320230Y59469I1602J1199D01*
G03X319342I-444J-231D01*
G02X319168Y59192I-1776J922D01*
G01X319068Y59059D01*
Y58992D01*
X319008D01*
X318867Y58872D01*
G02X316267I-1300J1521D01*
G01X316126Y58992D01*
X316066D01*
Y59059D01*
X315966Y59192D01*
G02X315776Y59500I1601J1200D01*
G03X314880I-448J-223D01*
G02X314690Y59192I-1791J892D01*
G01X314590Y59059D01*
Y58992D01*
X314530D01*
X314389Y58872D01*
G02X311789I-1300J1521D01*
G01X311648Y58992D01*
X311588D01*
Y59059D01*
X311488Y59192D01*
G02X311314Y59469I1602J1199D01*
G03X310426I-444J-231D01*
G02X310252Y59192I-1776J922D01*
G01X310152Y59059D01*
Y58992D01*
X310092D01*
X309951Y58872D01*
G02X307351I-1300J1521D01*
G01X307210Y58992D01*
X307150D01*
Y59059D01*
X307050Y59192D01*
G02X306851Y59518I1601J1201D01*
G03X305951I-450J-218D01*
G02X305752Y59192I-1800J875D01*
G01X305652Y59059D01*
Y58992D01*
X305592D01*
X305451Y58872D01*
G02X302851I-1300J1521D01*
G01X302710Y58992D01*
X302650D01*
Y59059D01*
X302550Y59192D01*
G02X302365Y59489I1600J1203D01*
G03X301473I-446J-225D01*
G02X301288Y59192I-1785J906D01*
G01X301188Y59059D01*
Y58992D01*
X301128D01*
X300987Y58872D01*
G02X298387I-1300J1521D01*
G37*
G54D52*
X61888Y666012D03*
X57124Y675327D03*
X54483Y679810D03*
X59236Y670758D03*
X144878Y1738861D03*
X158618Y1399448D03*
X164037Y1400226D03*
X170351Y1401324D03*
X150309Y1737009D03*
X168151Y1739208D03*
X156183Y1735240D03*
X165782Y1732903D03*
X163257Y1737619D03*
X176083Y1402321D03*
X173394Y1736051D03*
X308057Y248863D03*
X306267Y241010D03*
X314914Y238162D03*
X314940Y252083D03*
X305867Y258589D03*
X309678Y1053262D03*
X314183Y1403423D03*
X312077Y1575871D03*
X311539Y1753499D03*
X331403Y51409D03*
X333889Y56021D03*
X338227Y61559D03*
X320372Y225979D03*
X318088Y231820D03*
X321899Y238137D03*
X329930Y245684D03*
X331046Y232021D03*
X320961Y250105D03*
X324709Y231580D03*
X335522Y404033D03*
X323313Y418313D03*
X326196Y413982D03*
X328950Y409216D03*
X320980Y423225D03*
X336617Y577978D03*
X319305Y582111D03*
X329636Y584715D03*
X317724Y588250D03*
X337387Y586230D03*
X320380Y576491D03*
X331867Y589810D03*
X333750Y595326D03*
X323751Y589155D03*
X319852Y593330D03*
X321742Y599041D03*
X331568Y752967D03*
X339012Y752859D03*
X329336Y762693D03*
X334010Y758588D03*
X327524Y758020D03*
X339615Y926357D03*
X329938Y948756D03*
X332527Y943746D03*
X324098Y946104D03*
X318557Y941178D03*
X323868Y929978D03*
X326646Y939788D03*
X333300Y928464D03*
X336160Y937262D03*
X328583Y933262D03*
X321425Y951577D03*
X324246Y1051786D03*
X335677Y1048904D03*
X317592Y1053050D03*
X331920Y1116088D03*
X337509Y1109598D03*
X328989Y1121090D03*
X326558Y1126368D03*
X327452Y1279447D03*
X321978Y1282086D03*
X338047Y1282599D03*
X333242Y1276809D03*
X329619Y1284016D03*
X327932Y1289221D03*
X319404Y1401346D03*
X325636Y1399114D03*
X334646Y1400804D03*
X323720Y1570924D03*
X329399Y1571939D03*
X317243Y1574832D03*
X333474Y1566686D03*
X335963Y1573797D03*
X329887Y1752081D03*
X321283Y1753466D03*
X335730Y1753270D03*
X338309Y1927623D03*
X332399Y1926787D03*
X359931Y52189D03*
X348289Y50863D03*
X345089Y56190D03*
X340373Y51579D03*
X342097Y401684D03*
X363825Y401768D03*
X342900Y580126D03*
X362577Y752783D03*
X344109Y751809D03*
X343656Y933725D03*
X345578Y1047844D03*
X344099Y1106798D03*
X349855Y1104302D03*
X344130Y1401670D03*
X350690Y1403243D03*
X348710Y1570187D03*
X361011Y1568890D03*
X343402Y1572080D03*
X348245Y1575241D03*
X355364Y1570990D03*
X345537Y1916558D03*
X344402Y1911123D03*
X363361Y1918313D03*
X358318Y1920680D03*
X363411Y1923459D03*
X340336Y1922409D03*
X347676Y1922165D03*
X372204Y56126D03*
X365720Y52336D03*
X379257Y52158D03*
X379572Y58441D03*
X387524Y76847D03*
X374442Y406857D03*
X380619Y410112D03*
X380878Y403999D03*
X374542Y401282D03*
X368907Y404308D03*
X376654Y754748D03*
X382892Y767710D03*
X386790Y774338D03*
X380186Y761742D03*
X379335Y1189778D03*
X383276Y1184136D03*
X386816Y1179841D03*
X376472Y1194999D03*
X373674Y1199967D03*
X371523Y1204725D03*
X367829Y1566108D03*
X374775Y1919243D03*
X379403Y1917261D03*
X369748Y1921795D03*
X391278Y765894D03*
G54D53*
X15547Y723112D03*
Y730986D03*
X25389Y723112D03*
Y730986D03*
X15547Y738860D03*
Y746734D03*
Y754608D03*
X25389Y738860D03*
Y746734D03*
Y754608D03*
X15547Y762483D03*
Y770357D03*
Y778231D03*
X25389Y762483D03*
Y770357D03*
Y778231D03*
X15547Y786105D03*
Y793979D03*
X25389Y786105D03*
Y793979D03*
X33263Y727049D03*
Y734923D03*
Y742797D03*
Y750671D03*
Y758545D03*
Y766419D03*
Y774293D03*
Y782167D03*
Y790041D03*
X166500Y126110D03*
Y118626D03*
Y111407D03*
X166329Y140623D03*
X166500Y132705D03*
X166329Y148066D03*
Y156102D03*
Y163621D03*
X156430Y461714D03*
Y483012D03*
X156259Y490930D03*
X156430Y468933D03*
Y476417D03*
X156259Y513928D03*
Y498373D03*
Y506409D03*
X155444Y822725D03*
X162872D03*
Y830209D03*
X155444D03*
X171524Y844722D03*
Y852165D03*
X162872Y836804D03*
X155444D03*
X162701Y844722D03*
X155273D03*
X162701Y852165D03*
X155273D03*
X171524Y860201D03*
Y867720D03*
X162701Y860201D03*
X155273D03*
X162701Y867720D03*
X155273D03*
X169375Y1176256D03*
Y1190335D03*
Y1183740D03*
X153124Y1176256D03*
X160552D03*
Y1183740D03*
Y1190335D03*
X153124D03*
Y1183740D03*
X160552Y1169037D03*
X153124D03*
X169204Y1198253D03*
X160381D03*
X152953D03*
X154109Y1499221D03*
X161537D03*
Y1506440D03*
X170360D03*
X154109D03*
X153938Y1528437D03*
X154109Y1513924D03*
Y1520519D03*
X170360Y1513924D03*
Y1520519D03*
X161537D03*
Y1513924D03*
X161366Y1528437D03*
X170189D03*
X153938Y1535880D03*
Y1543916D03*
Y1551435D03*
X170189Y1535880D03*
Y1543916D03*
X161366Y1535880D03*
Y1543916D03*
Y1551435D03*
X170189D03*
X152091Y1866003D03*
X159519D03*
X152091Y1880706D03*
Y1887301D03*
X168342Y1880706D03*
Y1887301D03*
X159519D03*
Y1880706D03*
Y1873222D03*
X168342D03*
X152091D03*
X151920Y1902662D03*
Y1910698D03*
X168171Y1902662D03*
Y1910698D03*
X159348Y1902662D03*
Y1910698D03*
X151920Y1895219D03*
X159348D03*
X168171D03*
X151920Y1918217D03*
X159348D03*
X168171D03*
X173928Y126110D03*
Y118626D03*
Y111407D03*
X173757Y140623D03*
X173928Y132705D03*
X173757Y148066D03*
Y156102D03*
Y163621D03*
X175033Y261594D03*
Y268813D03*
Y282892D03*
X174862Y290810D03*
Y298253D03*
X175033Y276297D03*
X174862Y313808D03*
Y306289D03*
X179191Y822725D03*
Y830209D03*
X171695Y822725D03*
Y830209D03*
X179191Y836804D03*
X171695D03*
X179020Y844722D03*
Y852165D03*
Y860201D03*
Y867720D03*
X176871Y1176256D03*
Y1190335D03*
Y1183740D03*
X176700Y1198253D03*
X177856Y1506440D03*
Y1513924D03*
Y1520519D03*
X177685Y1528437D03*
Y1535880D03*
Y1543916D03*
Y1551435D03*
X175838Y1880706D03*
Y1887301D03*
Y1873222D03*
X175667Y1902662D03*
Y1910698D03*
Y1895219D03*
Y1918217D03*
X240955Y56999D03*
Y64483D03*
X240784Y78996D03*
X240955Y71078D03*
X240784Y94475D03*
Y101994D03*
Y86439D03*
X236537Y244995D03*
X227714Y237776D03*
Y244995D03*
X244033D03*
X236537Y259074D03*
X236366Y266992D03*
Y274435D03*
X227714Y259074D03*
X227543Y266992D03*
Y274435D03*
X244033Y259074D03*
X243862Y266992D03*
Y274435D03*
X236537Y252479D03*
X227714D03*
X244033D03*
X236366Y289990D03*
X227543D03*
X243862D03*
X236366Y282471D03*
X227543D03*
X243862D03*
X232548Y461083D03*
X241371Y482381D03*
X241200Y490299D03*
X232548Y482381D03*
X232377Y490299D03*
X241371Y468302D03*
Y475786D03*
X232548Y468302D03*
Y475786D03*
X241200Y513297D03*
X232377D03*
X241200Y497742D03*
X232377D03*
X241200Y505778D03*
X232377D03*
X230963Y608108D03*
X238391D03*
X230963Y601513D03*
X238391D03*
Y594029D03*
X230963D03*
X230792Y631505D03*
X238220D03*
X230792Y623469D03*
X238220D03*
X230792Y616026D03*
X238220D03*
X230792Y639024D03*
X238220D03*
X231339Y959673D03*
X238767D03*
Y967157D03*
Y973752D03*
X231339D03*
Y967157D03*
X238767Y952454D03*
X231339D03*
X238596Y981670D03*
X231168D03*
X238596Y997149D03*
Y989113D03*
X231168Y997149D03*
Y989113D03*
X238596Y1004668D03*
X231168D03*
X238659Y1215296D03*
X231231D03*
X238659Y1207777D03*
Y1199741D03*
X231231Y1207777D03*
Y1199741D03*
X225131Y1663167D03*
X241382Y1670386D03*
X232559Y1663167D03*
Y1670386D03*
X225131D03*
X241211Y1699826D03*
X241382Y1677870D03*
X241211Y1692383D03*
X241382Y1684465D03*
X232559D03*
Y1677870D03*
X232388Y1692383D03*
Y1699826D03*
X225131Y1684465D03*
Y1677870D03*
X224960Y1692383D03*
Y1699826D03*
X241211Y1715381D03*
Y1707862D03*
X232388D03*
Y1715381D03*
X224960Y1707862D03*
Y1715381D03*
X248451Y56999D03*
Y64483D03*
X248280Y78996D03*
X248451Y71078D03*
X248280Y94475D03*
Y101994D03*
Y86439D03*
X248867Y482381D03*
X248696Y490299D03*
X248867Y468302D03*
Y475786D03*
X248696Y513297D03*
Y497742D03*
Y505778D03*
X254710Y608108D03*
Y601513D03*
Y594029D03*
X247214Y608108D03*
Y601513D03*
Y594029D03*
X254539Y631505D03*
Y623469D03*
Y616026D03*
X247043Y631505D03*
Y623469D03*
Y616026D03*
X267433Y624321D03*
X254539Y639024D03*
X247043D03*
X255086Y959673D03*
Y973752D03*
Y967157D03*
X247590Y959673D03*
Y973752D03*
Y967157D03*
X254915Y981670D03*
Y997149D03*
Y989113D03*
X247419Y981670D03*
Y997149D03*
Y989113D03*
X254915Y1004668D03*
X247419D03*
X254978Y1215296D03*
X247482D03*
X254978Y1207777D03*
Y1199741D03*
X247482Y1207777D03*
Y1199741D03*
X248878Y1670386D03*
X248707Y1699826D03*
X248878Y1677870D03*
Y1684465D03*
X248707Y1692383D03*
Y1707862D03*
Y1715381D03*
X279044Y624627D03*
X354391Y1329686D03*
Y1350706D03*
Y1360043D03*
Y1340201D03*
Y1376210D03*
Y1367771D03*
X366169Y1329686D03*
Y1350706D03*
Y1360043D03*
Y1340201D03*
Y1376210D03*
Y1367771D03*
G54D47*
X18995Y508701D03*
X23995Y518701D03*
X21495Y559882D03*
X28995Y508701D03*
X38995D03*
X48995D03*
X33995Y518701D03*
X43995D03*
X23995Y1622992D03*
X51495Y1571811D03*
X43995Y1622992D03*
X33995D03*
X48995Y1612992D03*
X38995D03*
X28995D03*
X53995Y1622992D03*
G54D66*
X173385Y21890D03*
X183385Y32520D03*
Y21890D03*
X193385Y32520D03*
Y21890D03*
X173385Y196890D03*
X183385D03*
X193385D03*
X183385Y207520D03*
X193385D03*
X173385Y371890D03*
X183385D03*
X193385D03*
X183385Y382520D03*
X193385D03*
X173386Y546890D03*
X183386Y557520D03*
Y546890D03*
X193386Y557520D03*
Y546890D03*
X173386Y721890D03*
X183386Y732520D03*
Y721890D03*
X193386Y732520D03*
Y721890D03*
X173385Y896890D03*
X183385D03*
X193385D03*
X183385Y907520D03*
X193385D03*
X173385Y1071890D03*
X183385D03*
X193385D03*
X183385Y1082520D03*
X193385D03*
X173385Y1246890D03*
X183385Y1257520D03*
Y1246890D03*
X193385Y1257520D03*
Y1246890D03*
X173385Y1421890D03*
X183385Y1432520D03*
Y1421890D03*
X193385Y1432520D03*
Y1421890D03*
X173385Y1596890D03*
X183385D03*
X193385D03*
X183385Y1607520D03*
X193385D03*
X173385Y1771890D03*
X183385D03*
X193385D03*
X183385Y1782520D03*
X193385D03*
X173385Y1946890D03*
X183385Y1957520D03*
Y1946890D03*
X193385Y1957520D03*
Y1946890D03*
X203385Y32520D03*
Y21890D03*
X213385Y32520D03*
Y21890D03*
X203385Y196890D03*
X213385D03*
X203385Y207520D03*
X213385D03*
X203385Y371890D03*
X213385D03*
X203385Y382520D03*
X213385D03*
X203386Y557520D03*
Y546890D03*
X213386Y557520D03*
Y546890D03*
X203386Y732520D03*
Y721890D03*
X213386Y732520D03*
Y721890D03*
X203385Y896890D03*
X213385D03*
X203385Y907520D03*
X213385D03*
X203385Y1071890D03*
X213385D03*
X203385Y1082520D03*
X213385D03*
X203385Y1257520D03*
Y1246890D03*
X213385Y1257520D03*
Y1246890D03*
X203385Y1432520D03*
Y1421890D03*
X213385Y1432520D03*
Y1421890D03*
X203385Y1596890D03*
X213385D03*
X203385Y1607520D03*
X213385D03*
X203385Y1771890D03*
X213385D03*
X203385Y1782520D03*
X213385D03*
X203385Y1957520D03*
Y1946890D03*
X213385Y1957520D03*
Y1946890D03*
X223385Y32520D03*
Y21890D03*
X233385Y32520D03*
Y21890D03*
X243385Y32520D03*
Y21890D03*
X223385Y196890D03*
X233385D03*
X243385D03*
X223385Y207520D03*
X233385D03*
X243385D03*
X223385Y371890D03*
X233385D03*
X243385D03*
X223385Y382520D03*
X233385D03*
X243385D03*
X223386Y557520D03*
Y546890D03*
X233386Y557520D03*
Y546890D03*
X243386Y557520D03*
Y546890D03*
X223386Y732520D03*
Y721890D03*
X233386Y732520D03*
Y721890D03*
X243386Y732520D03*
Y721890D03*
X223385Y896890D03*
X233385D03*
X243385D03*
X223385Y907520D03*
X233385D03*
X243385D03*
X223385Y1071890D03*
X233385D03*
X243385D03*
X223385Y1082520D03*
X233385D03*
X243385D03*
X223385Y1257520D03*
Y1246890D03*
X233385Y1257520D03*
Y1246890D03*
X243385Y1257520D03*
Y1246890D03*
X223385Y1432520D03*
Y1421890D03*
X233385Y1432520D03*
Y1421890D03*
X243385Y1432520D03*
Y1421890D03*
X223385Y1596890D03*
X233385D03*
X243385D03*
X223385Y1607520D03*
X233385D03*
X243385D03*
X223385Y1771890D03*
X233385D03*
X243385D03*
X223385Y1782520D03*
X233385D03*
X243385D03*
X223385Y1957520D03*
Y1946890D03*
X233385Y1957520D03*
Y1946890D03*
X243385Y1957520D03*
Y1946890D03*
X337165Y24705D03*
Y34705D03*
Y199705D03*
Y209705D03*
Y374705D03*
Y384705D03*
X337166Y549705D03*
Y559705D03*
Y724705D03*
Y734705D03*
X337165Y899705D03*
Y909705D03*
Y1074705D03*
Y1084705D03*
Y1249705D03*
Y1259705D03*
Y1424705D03*
Y1434705D03*
Y1599705D03*
Y1609705D03*
Y1774705D03*
Y1784705D03*
Y1949705D03*
Y1959705D03*
X342165Y19705D03*
Y29705D03*
X347165Y24705D03*
X352165Y19705D03*
Y29705D03*
X357165Y24705D03*
X362165Y19705D03*
Y29705D03*
X347165Y34705D03*
X357165D03*
X342165Y194705D03*
X347165Y199705D03*
X352165Y194705D03*
X357165Y199705D03*
X362165Y194705D03*
X342165Y204705D03*
X347165Y209705D03*
X352165Y204705D03*
X357165Y209705D03*
X362165Y204705D03*
X342165Y369705D03*
X352165D03*
X362165D03*
X342165Y379705D03*
X347165Y374705D03*
Y384705D03*
X352165Y379705D03*
X357165Y374705D03*
Y384705D03*
X362165Y379705D03*
X342166Y544705D03*
Y554705D03*
X347166Y549705D03*
Y559705D03*
X352166Y544705D03*
Y554705D03*
X357166Y549705D03*
Y559705D03*
X362166Y544705D03*
Y554705D03*
X342166Y719705D03*
Y729705D03*
X347166Y724705D03*
X352166Y719705D03*
Y729705D03*
X357166Y724705D03*
X362166Y719705D03*
Y729705D03*
X347166Y734705D03*
X357166D03*
X342165Y894705D03*
X347165Y899705D03*
X352165Y894705D03*
X357165Y899705D03*
X362165Y894705D03*
X342165Y904705D03*
X347165Y909705D03*
X352165Y904705D03*
X357165Y909705D03*
X362165Y904705D03*
X342165Y1069705D03*
X352165D03*
X362165D03*
X342165Y1079705D03*
X347165Y1074705D03*
Y1084705D03*
X352165Y1079705D03*
X357165Y1074705D03*
Y1084705D03*
X362165Y1079705D03*
X342165Y1244705D03*
Y1254705D03*
X347165Y1249705D03*
Y1259705D03*
X352165Y1244705D03*
Y1254705D03*
X357165Y1249705D03*
Y1259705D03*
X362165Y1244705D03*
Y1254705D03*
X342165Y1419705D03*
Y1429705D03*
X347165Y1424705D03*
Y1434705D03*
X352165Y1419705D03*
Y1429705D03*
X357165Y1424705D03*
Y1434705D03*
X362165Y1419705D03*
Y1429705D03*
X342165Y1594705D03*
X347165Y1599705D03*
X352165Y1594705D03*
X357165Y1599705D03*
X362165Y1594705D03*
X342165Y1604705D03*
X347165Y1609705D03*
X352165Y1604705D03*
X357165Y1609705D03*
X362165Y1604705D03*
X342165Y1769705D03*
X352165D03*
X362165D03*
X342165Y1779705D03*
X347165Y1774705D03*
Y1784705D03*
X352165Y1779705D03*
X357165Y1774705D03*
Y1784705D03*
X362165Y1779705D03*
X342165Y1944705D03*
Y1954705D03*
X347165Y1949705D03*
Y1959705D03*
X352165Y1944705D03*
Y1954705D03*
X357165Y1949705D03*
Y1959705D03*
X362165Y1944705D03*
Y1954705D03*
G54D65*
X119920Y18071D03*
Y98071D03*
Y108071D03*
Y118071D03*
Y128071D03*
Y138071D03*
Y148071D03*
Y158071D03*
Y168071D03*
Y178071D03*
Y188071D03*
Y198071D03*
Y208071D03*
Y366102D03*
Y436102D03*
Y446102D03*
Y456102D03*
Y466102D03*
Y476102D03*
Y486102D03*
Y496102D03*
Y506102D03*
Y516102D03*
Y526102D03*
Y536102D03*
Y546102D03*
Y556102D03*
Y804134D03*
Y814134D03*
Y824134D03*
Y834134D03*
Y844134D03*
Y854134D03*
Y864134D03*
Y874134D03*
Y884134D03*
Y894134D03*
Y904134D03*
Y1232165D03*
Y1242165D03*
Y1252165D03*
Y1828228D03*
Y1838228D03*
Y1848228D03*
Y1858228D03*
Y1868228D03*
Y1878228D03*
Y1888228D03*
Y1898228D03*
Y1908228D03*
Y1918228D03*
Y1928228D03*
Y1938228D03*
Y1948228D03*
X139920Y28071D03*
Y18071D03*
Y58071D03*
Y38071D03*
Y98071D03*
Y128071D03*
Y118071D03*
Y108071D03*
Y148071D03*
Y138071D03*
Y178071D03*
Y168071D03*
Y158071D03*
Y198071D03*
Y188071D03*
Y208071D03*
Y366102D03*
Y386102D03*
Y376102D03*
Y406102D03*
Y466102D03*
Y456102D03*
Y446102D03*
Y486102D03*
Y476102D03*
Y516102D03*
Y506102D03*
Y496102D03*
Y536102D03*
Y526102D03*
Y556102D03*
Y546102D03*
Y804134D03*
Y824134D03*
Y814134D03*
Y854134D03*
Y844134D03*
Y834134D03*
Y874134D03*
Y864134D03*
Y904134D03*
Y894134D03*
Y884134D03*
Y1142165D03*
Y1162165D03*
Y1152165D03*
Y1192165D03*
Y1182165D03*
Y1172165D03*
Y1212165D03*
Y1202165D03*
Y1242165D03*
Y1232165D03*
Y1222165D03*
Y1252165D03*
Y1410197D03*
Y1430197D03*
Y1420197D03*
Y1500197D03*
Y1530197D03*
Y1520197D03*
Y1510197D03*
Y1550197D03*
Y1540197D03*
Y1580197D03*
Y1570197D03*
Y1560197D03*
Y1600197D03*
Y1590197D03*
Y1768228D03*
Y1758228D03*
Y1798228D03*
Y1778228D03*
Y1838228D03*
Y1868228D03*
Y1858228D03*
Y1848228D03*
Y1888228D03*
Y1878228D03*
Y1918228D03*
Y1908228D03*
Y1898228D03*
Y1938228D03*
Y1928228D03*
Y1948228D03*
G54D45*
X22735Y34953D03*
Y216976D03*
X27735Y206976D03*
X17735Y233811D03*
X27735D03*
X22735Y243811D03*
X27735Y415834D03*
X22735Y425834D03*
X32735Y34953D03*
X42735D03*
Y216976D03*
X32735D03*
X47735Y206976D03*
X37735D03*
Y233811D03*
X47735D03*
X32735Y243811D03*
X42735D03*
X47735Y415834D03*
X37735D03*
X42735Y425834D03*
X32735D03*
X52735Y216976D03*
Y425834D03*
X22735Y1957291D03*
X27735Y1947291D03*
Y2051661D03*
X42735Y1957291D03*
X32735D03*
X47735Y1947291D03*
X37735D03*
X47735Y2051661D03*
X37735D03*
X52735Y1957291D03*
X189762Y73105D03*
X190289Y152050D03*
X190357Y247568D03*
X190817Y331786D03*
X189761Y421732D03*
X190553Y506517D03*
X192888Y598130D03*
X190816Y681645D03*
X191846Y774526D03*
X191606Y856244D03*
X196311Y947202D03*
X195516Y1032544D03*
X191250Y1122856D03*
X191342Y1206233D03*
X191846Y1299104D03*
X189463Y1474162D03*
X191079Y1557277D03*
X192143Y1648177D03*
X191607Y1731351D03*
X191530Y1823227D03*
X190289Y1900420D03*
X192125Y1998730D03*
X191530Y2043388D03*
G54D63*
X23402Y1668874D03*
Y1685410D03*
Y1701945D03*
Y1718480D03*
Y1735016D03*
Y1751551D03*
Y1768087D03*
Y1784622D03*
Y1817693D03*
Y1801158D03*
X45056Y1668874D03*
Y1718480D03*
Y1768087D03*
G54D50*
X67499Y528544D03*
Y1603149D03*
G54D48*
X20468Y696341D03*
G54D51*
X53995Y518701D03*
G54D62*
X18995Y1612992D03*
G54D42*
X65354Y114960D03*
Y464960D03*
X307086Y127165D03*
Y477165D03*
Y827165D03*
Y1343504D03*
X65354Y1514960D03*
X307086Y1693504D03*
X65354Y1864960D03*
X307087Y2043503D03*
G54D61*
X385616Y1991570D03*
G54D57*
X163385Y1952205D03*
Y1777205D03*
Y1602205D03*
Y1427205D03*
Y1252205D03*
Y1077205D03*
Y902205D03*
X163386Y727205D03*
Y552205D03*
X163385Y377205D03*
Y202205D03*
Y27205D03*
G54D44*
X57735Y59953D03*
Y181976D03*
Y268811D03*
Y390834D03*
Y1922291D03*
Y2026661D03*
G54D67*
X65354Y814960D03*
Y1164960D03*
G54D60*
X373385Y32520D03*
Y207520D03*
Y382520D03*
X373386Y557520D03*
Y732520D03*
X373385Y907520D03*
Y1082520D03*
Y1257520D03*
Y1432520D03*
Y1607520D03*
Y1782520D03*
Y1957520D03*
G54D49*
X52735Y34953D03*
Y243811D03*
X17735Y1947291D03*
Y2051661D03*
G54D54*
X173385Y1957520D03*
Y1782520D03*
Y1607520D03*
Y1432520D03*
Y1257520D03*
Y1082520D03*
Y907520D03*
Y382520D03*
Y207520D03*
Y32520D03*
G54D46*
X17735Y206976D03*
Y415834D03*
G54D43*
X13995Y543701D03*
X58995D03*
X13995Y1587992D03*
X58995D03*
G54D58*
X307086Y308268D03*
G54D55*
X173386Y732520D03*
Y557520D03*
G54D64*
X45056Y1817693D03*
G54D56*
X307086Y1883071D03*
G54D59*
X359842Y78780D03*
Y253780D03*
Y428780D03*
Y603780D03*
Y778780D03*
Y953780D03*
Y1128780D03*
Y1303780D03*
Y1478780D03*
Y1653780D03*
Y1828780D03*
Y2003780D03*
%LPD*%
G75*
G36*
G01X65354Y95260D02*
G02I0J19700D01*
G37*
G36*
G01Y445260D02*
G02I0J19700D01*
G37*
G36*
G01Y1495260D02*
G02I0J19700D01*
G37*
G36*
G01Y1845260D02*
G02I0J19700D01*
G37*
G36*
G01X326786Y127165D02*
G02I-19700J0D01*
G37*
G36*
G01Y477165D02*
G02I-19700J0D01*
G37*
G36*
G01Y827165D02*
G02I-19700J0D01*
G37*
G36*
G01Y1343504D02*
G02I-19700J0D01*
G37*
G36*
G01Y1693504D02*
G02I-19700J0D01*
G37*
G36*
G01X326787Y2043503D02*
G02I-19700J0D01*
G37*
%LPC*%
G75*
G54D67*
X65354Y114960D03*
Y464960D03*
Y1514960D03*
Y1864960D03*
X307086Y127165D03*
Y477165D03*
Y827165D03*
Y1343504D03*
Y1693504D03*
X307087Y2043503D03*
%LPD*%
G75*
G36*
G01X2004Y534594D02*
Y1597356D01*
X3998D01*
Y534594D01*
X2004D01*
G37*
G54D10*
X17735Y24953D03*
X27735D03*
X22735Y34953D03*
Y216976D03*
X27735Y206976D03*
X17735Y233811D03*
X27735D03*
X22735Y243811D03*
X27735Y415834D03*
X22735Y425834D03*
Y1957291D03*
X27735Y1947291D03*
X22735Y2061661D03*
X27735Y2051661D03*
X37735Y24953D03*
X47735D03*
X32735Y34953D03*
X42735D03*
Y216976D03*
X32735D03*
X47735Y206976D03*
X37735D03*
Y233811D03*
X47735D03*
X32735Y243811D03*
X42735D03*
X47735Y415834D03*
X37735D03*
X42735Y425834D03*
X32735D03*
X42735Y1957291D03*
X32735D03*
X47735Y1947291D03*
X37735D03*
X42735Y2061661D03*
X32735D03*
X47735Y2051661D03*
X37735D03*
X52735Y216976D03*
Y425834D03*
Y1957291D03*
Y2061661D03*
X189762Y73105D03*
X190289Y152050D03*
X190357Y247568D03*
X190817Y331786D03*
X189761Y421732D03*
X190553Y506517D03*
X192888Y598130D03*
X190816Y681645D03*
X191846Y774526D03*
X191606Y856244D03*
X196311Y947202D03*
X195516Y1032544D03*
X191250Y1122856D03*
X191342Y1206233D03*
X191846Y1299104D03*
X190552Y1380966D03*
X189463Y1474162D03*
X191079Y1557277D03*
X192143Y1648177D03*
X191607Y1731351D03*
X191530Y1823227D03*
X190289Y1900420D03*
X192125Y1998730D03*
X191530Y2043388D03*
G54D20*
X15547Y707364D03*
X25389D03*
X7673Y703427D03*
X15547Y715238D03*
Y723112D03*
Y730986D03*
X25389Y715238D03*
Y723112D03*
Y730986D03*
X7673Y711301D03*
Y719175D03*
Y727049D03*
X15547Y738860D03*
Y746734D03*
Y754608D03*
X25389Y738860D03*
Y746734D03*
Y754608D03*
X7673Y734923D03*
Y742797D03*
Y750671D03*
Y758545D03*
X15547Y762483D03*
Y770357D03*
Y778231D03*
X25389Y762483D03*
Y770357D03*
Y778231D03*
X7673Y766419D03*
Y774293D03*
Y782167D03*
X15547Y786105D03*
Y793979D03*
Y801853D03*
X25389Y786105D03*
Y793979D03*
Y801853D03*
X7673Y790041D03*
Y797915D03*
Y805790D03*
X15547Y809727D03*
Y817601D03*
Y825475D03*
X25389Y809727D03*
Y817601D03*
Y825475D03*
X7673Y813664D03*
Y821538D03*
Y829412D03*
X15547Y833349D03*
Y841223D03*
Y849097D03*
X25389Y833349D03*
Y841223D03*
Y849097D03*
X7673Y837286D03*
Y845160D03*
Y853034D03*
X15547Y856971D03*
Y864845D03*
Y872719D03*
X25389Y856971D03*
Y864845D03*
Y872719D03*
X7673Y860908D03*
Y868782D03*
Y876656D03*
X15547Y880593D03*
Y888467D03*
Y896341D03*
X25389Y880593D03*
Y888467D03*
Y896341D03*
X7673Y884530D03*
Y892404D03*
Y900278D03*
X15547Y904215D03*
Y912089D03*
Y919963D03*
X25389Y904215D03*
Y912089D03*
Y919963D03*
X7673Y908152D03*
Y916026D03*
Y923900D03*
X15547Y927837D03*
Y935711D03*
Y943585D03*
Y951459D03*
X25389Y927837D03*
Y935711D03*
Y943585D03*
Y951459D03*
X7673Y931774D03*
Y939648D03*
Y947522D03*
X15547Y959333D03*
Y967207D03*
Y975081D03*
X25389Y959333D03*
Y967207D03*
Y975081D03*
X7673Y955396D03*
Y963270D03*
Y971144D03*
Y979018D03*
Y994766D03*
X15547Y990829D03*
Y998703D03*
X25389Y990829D03*
Y998703D03*
X7673Y1002640D03*
Y1010514D03*
Y1018388D03*
X15547Y1006577D03*
Y1014451D03*
Y1022325D03*
X25389Y1006577D03*
Y1014451D03*
Y1022325D03*
X7673Y1026262D03*
X15547Y1030199D03*
X15551Y1065629D03*
X25393D03*
X7677Y1061692D03*
Y1069566D03*
X15551Y1073503D03*
Y1081377D03*
Y1089251D03*
X25393Y1073503D03*
Y1081377D03*
Y1089251D03*
X7677Y1077440D03*
Y1085314D03*
Y1093188D03*
X15551Y1097125D03*
Y1104999D03*
Y1112873D03*
Y1120748D03*
X25393Y1097125D03*
Y1104999D03*
Y1112873D03*
Y1120748D03*
X7677Y1101062D03*
Y1108936D03*
Y1116810D03*
X15551Y1128622D03*
Y1136496D03*
Y1144370D03*
X25393Y1128622D03*
Y1136496D03*
Y1144370D03*
X7677Y1124684D03*
Y1132558D03*
Y1140432D03*
X15551Y1152244D03*
Y1160118D03*
Y1167992D03*
X25393Y1152244D03*
Y1160118D03*
Y1167992D03*
X7677Y1148306D03*
Y1156180D03*
Y1164055D03*
X15551Y1175866D03*
Y1183740D03*
Y1191614D03*
X25393Y1175866D03*
Y1183740D03*
Y1191614D03*
X7677Y1171929D03*
Y1179803D03*
Y1187677D03*
X15551Y1199488D03*
Y1207362D03*
Y1215236D03*
X25393Y1199488D03*
Y1207362D03*
Y1215236D03*
X7677Y1195551D03*
Y1203425D03*
Y1211299D03*
X15551Y1223110D03*
Y1230984D03*
Y1238858D03*
X25393Y1223110D03*
Y1230984D03*
Y1238858D03*
X7677Y1219173D03*
Y1227047D03*
Y1234921D03*
X15551Y1246732D03*
Y1254606D03*
Y1262480D03*
X25393Y1246732D03*
Y1254606D03*
Y1262480D03*
X7677Y1242795D03*
Y1250669D03*
Y1258543D03*
X15551Y1270354D03*
Y1278228D03*
Y1286102D03*
X25393Y1270354D03*
Y1278228D03*
Y1286102D03*
X7677Y1266417D03*
Y1274291D03*
Y1282165D03*
X15551Y1293976D03*
Y1301850D03*
Y1309724D03*
X25393Y1293976D03*
Y1301850D03*
Y1309724D03*
X7677Y1290039D03*
Y1297913D03*
Y1305787D03*
Y1313661D03*
X15551Y1317598D03*
Y1325472D03*
Y1333346D03*
X25393Y1317598D03*
Y1325472D03*
Y1333346D03*
X7677Y1321535D03*
Y1329409D03*
Y1337283D03*
Y1353031D03*
Y1360905D03*
X15551Y1349094D03*
Y1356968D03*
X25393Y1349094D03*
Y1356968D03*
X7677Y1368779D03*
Y1376653D03*
Y1384527D03*
X15551Y1364842D03*
Y1372716D03*
Y1380590D03*
X25393Y1364842D03*
Y1372716D03*
Y1380590D03*
X15551Y1388464D03*
X33263Y703427D03*
Y711301D03*
Y719175D03*
Y727049D03*
Y734923D03*
Y742797D03*
Y750671D03*
Y758545D03*
Y766419D03*
Y774293D03*
Y782167D03*
Y790041D03*
Y797915D03*
Y805790D03*
Y813664D03*
Y821538D03*
Y829412D03*
Y837286D03*
Y845160D03*
Y853034D03*
Y860908D03*
Y868782D03*
Y876656D03*
Y884530D03*
Y892404D03*
Y900278D03*
Y908152D03*
Y916026D03*
Y923900D03*
Y931774D03*
Y939648D03*
Y947522D03*
Y955396D03*
Y963270D03*
Y971144D03*
Y979018D03*
Y994766D03*
Y1002640D03*
Y1010514D03*
Y1018388D03*
Y1026262D03*
X33267Y1061692D03*
Y1069566D03*
Y1077440D03*
Y1085314D03*
Y1093188D03*
Y1101062D03*
Y1108936D03*
Y1116810D03*
Y1124684D03*
Y1132558D03*
Y1140432D03*
Y1148306D03*
Y1156180D03*
Y1164055D03*
Y1171929D03*
Y1179803D03*
Y1187677D03*
Y1195551D03*
Y1203425D03*
Y1211299D03*
Y1219173D03*
Y1227047D03*
Y1234921D03*
Y1242795D03*
Y1250669D03*
Y1258543D03*
Y1266417D03*
Y1274291D03*
Y1282165D03*
Y1290039D03*
Y1297913D03*
Y1305787D03*
Y1313661D03*
Y1321535D03*
Y1329409D03*
Y1337283D03*
Y1353031D03*
Y1360905D03*
Y1368779D03*
Y1376653D03*
Y1384527D03*
X166500Y126110D03*
Y118626D03*
Y111407D03*
X166329Y140623D03*
X166500Y132705D03*
X166329Y148066D03*
Y156102D03*
Y163621D03*
X165975Y265783D03*
Y296140D03*
Y286803D03*
Y276298D03*
Y312307D03*
Y303868D03*
X156430Y461714D03*
Y483012D03*
X156259Y490930D03*
X156430Y468933D03*
Y476417D03*
X156259Y513928D03*
Y498373D03*
Y506409D03*
X157272Y604773D03*
Y633416D03*
Y613574D03*
Y624079D03*
Y641144D03*
Y649583D03*
X155444Y822725D03*
X162872D03*
Y830209D03*
X155444D03*
X171524Y844722D03*
Y852165D03*
X162872Y836804D03*
X155444D03*
X162701Y844722D03*
X155273D03*
X162701Y852165D03*
X155273D03*
X171524Y860201D03*
Y867720D03*
X162701Y860201D03*
X155273D03*
X162701Y867720D03*
X155273D03*
X166699Y972924D03*
Y983439D03*
Y993944D03*
X166424Y1011298D03*
Y1003570D03*
Y1019737D03*
X169375Y1176256D03*
Y1190335D03*
Y1183740D03*
X153124Y1176256D03*
X160552D03*
Y1183740D03*
Y1190335D03*
X153124D03*
Y1183740D03*
X160552Y1169037D03*
X153124D03*
X169204Y1198253D03*
X160381D03*
X152953D03*
X155749Y1307733D03*
Y1328753D03*
Y1318248D03*
Y1354257D03*
Y1338090D03*
Y1345818D03*
X154109Y1499221D03*
X161537D03*
Y1506440D03*
X170360D03*
X154109D03*
X153938Y1528437D03*
X154109Y1513924D03*
Y1520519D03*
X170360Y1513924D03*
Y1520519D03*
X161537D03*
Y1513924D03*
X161366Y1528437D03*
X170189D03*
X153938Y1535880D03*
Y1543916D03*
Y1551435D03*
X170189Y1535880D03*
Y1543916D03*
X161366Y1535880D03*
Y1543916D03*
Y1551435D03*
X170189D03*
X158492Y1667763D03*
Y1657248D03*
Y1695333D03*
Y1687605D03*
Y1678268D03*
Y1703772D03*
X152091Y1866003D03*
X159519D03*
X152091Y1880706D03*
Y1887301D03*
X168342Y1880706D03*
Y1887301D03*
X159519D03*
Y1880706D03*
Y1873222D03*
X168342D03*
X152091D03*
X151920Y1902662D03*
Y1910698D03*
X168171Y1902662D03*
Y1910698D03*
X159348Y1902662D03*
Y1910698D03*
X151920Y1895219D03*
X159348D03*
X168171D03*
X151920Y1918217D03*
X159348D03*
X168171D03*
X173928Y126110D03*
Y118626D03*
Y111407D03*
X173757Y140623D03*
X173928Y132705D03*
X173757Y148066D03*
Y156102D03*
Y163621D03*
X175033Y261594D03*
Y268813D03*
Y282892D03*
X174862Y290810D03*
Y298253D03*
X175033Y276297D03*
X174862Y313808D03*
Y306289D03*
X179191Y822725D03*
Y830209D03*
X171695Y822725D03*
Y830209D03*
X179191Y836804D03*
X171695D03*
X179020Y844722D03*
Y852165D03*
Y860201D03*
Y867720D03*
X176871Y1176256D03*
Y1190335D03*
Y1183740D03*
X176700Y1198253D03*
X177856Y1506440D03*
Y1513924D03*
Y1520519D03*
X177685Y1528437D03*
Y1535880D03*
Y1543916D03*
Y1551435D03*
X175838Y1880706D03*
Y1887301D03*
Y1873222D03*
X175667Y1902662D03*
Y1910698D03*
Y1895219D03*
Y1918217D03*
X219214Y1287272D03*
Y1301975D03*
X219349Y1308924D03*
X219214Y1294491D03*
X219178Y1324285D03*
Y1332321D03*
Y1316842D03*
Y1339840D03*
X240955Y56999D03*
Y64483D03*
X240784Y78996D03*
X240955Y71078D03*
X240784Y94475D03*
Y101994D03*
Y86439D03*
X243741Y153964D03*
X222732D03*
X232700D03*
X243741Y170131D03*
Y161692D03*
X222732Y170131D03*
Y161692D03*
X232700Y170131D03*
Y161692D03*
X236537Y244995D03*
X227714Y237776D03*
Y244995D03*
X244033D03*
X236537Y259074D03*
X236366Y266992D03*
Y274435D03*
X227714Y259074D03*
X227543Y266992D03*
Y274435D03*
X244033Y259074D03*
X243862Y266992D03*
Y274435D03*
X236537Y252479D03*
X227714D03*
X244033D03*
X236366Y289990D03*
X227543D03*
X243862D03*
X236366Y282471D03*
X227543D03*
X243862D03*
X239746Y407393D03*
Y396878D03*
Y417898D03*
X232548Y461083D03*
X241371Y482381D03*
X241200Y490299D03*
X232548Y482381D03*
X232377Y490299D03*
X241371Y468302D03*
Y475786D03*
X232548Y468302D03*
Y475786D03*
X241200Y513297D03*
X232377D03*
X241200Y497742D03*
X232377D03*
X241200Y505778D03*
X232377D03*
X230963Y608108D03*
X238391D03*
X230963Y601513D03*
X238391D03*
Y594029D03*
X230963D03*
X230792Y631505D03*
X238220D03*
X230792Y623469D03*
X238220D03*
X230792Y616026D03*
X238220D03*
X230792Y639024D03*
X238220D03*
X243980Y754782D03*
X234012D03*
X243980Y762510D03*
Y770949D03*
X234012Y762510D03*
Y770949D03*
X231339Y959673D03*
X238767D03*
Y967157D03*
Y973752D03*
X231339D03*
Y967157D03*
X238767Y952454D03*
X231339D03*
X238596Y981670D03*
X231168D03*
X238596Y997149D03*
Y989113D03*
X231168Y997149D03*
Y989113D03*
X238596Y1004668D03*
X231168D03*
X238659Y1215296D03*
X231231D03*
X238659Y1207777D03*
Y1199741D03*
X231231Y1207777D03*
Y1199741D03*
X226642Y1287272D03*
Y1301975D03*
X235465D03*
X226777Y1308924D03*
X235600D03*
X242961Y1301975D03*
X243096Y1308924D03*
X226642Y1294491D03*
X235465D03*
X242961D03*
X226606Y1324285D03*
X235429D03*
X226606Y1332321D03*
X235429D03*
X242925Y1324285D03*
Y1332321D03*
X226606Y1316842D03*
X235429D03*
X242925D03*
X226606Y1339840D03*
X235429D03*
X242925D03*
X225131Y1663167D03*
X241382Y1670386D03*
X232559Y1663167D03*
Y1670386D03*
X225131D03*
X241211Y1699826D03*
X241382Y1677870D03*
X241211Y1692383D03*
X241382Y1684465D03*
X232559D03*
Y1677870D03*
X232388Y1692383D03*
Y1699826D03*
X225131Y1684465D03*
Y1677870D03*
X224960Y1692383D03*
Y1699826D03*
X241211Y1715381D03*
Y1707862D03*
X232388D03*
Y1715381D03*
X224960Y1707862D03*
Y1715381D03*
X224573Y2031480D03*
X234541D03*
X224573Y2020965D03*
X234541D03*
X224573Y2059050D03*
X234541Y2051322D03*
Y2059050D03*
X224573Y2041985D03*
Y2051322D03*
X234541Y2041985D03*
Y2067489D03*
X224573D03*
X256566Y54944D03*
X264104D03*
X256566Y45572D03*
X264104D03*
X248451Y56999D03*
X256566Y65449D03*
X264104D03*
X248451Y64483D03*
X248280Y78996D03*
X248451Y71078D03*
X248280Y94475D03*
Y101994D03*
Y86439D03*
X264861Y153964D03*
X253083D03*
X264861Y170131D03*
Y161692D03*
X253083Y170131D03*
Y161692D03*
X264596Y221664D03*
X252818D03*
X264596Y242684D03*
Y232179D03*
X252818Y242684D03*
Y232179D03*
X264596Y268188D03*
Y259749D03*
Y252021D03*
X252818Y268188D03*
Y252021D03*
Y259749D03*
X266040Y407146D03*
Y396631D03*
Y417651D03*
X257572Y396630D03*
Y407145D03*
X248714Y407536D03*
Y397021D03*
X257572Y417650D03*
X248714Y418041D03*
X248867Y482381D03*
X248696Y490299D03*
X248867Y468302D03*
Y475786D03*
X248696Y513297D03*
Y497742D03*
Y505778D03*
X267166Y581440D03*
Y572639D03*
Y609010D03*
Y601282D03*
Y591945D03*
X254710Y608108D03*
Y601513D03*
Y594029D03*
X247214Y608108D03*
Y601513D03*
Y594029D03*
X267166Y617449D03*
X254539Y631505D03*
Y623469D03*
Y616026D03*
X247043Y631505D03*
Y623469D03*
Y616026D03*
X267433Y624321D03*
X254539Y639024D03*
X247043D03*
X255021Y754782D03*
Y762510D03*
Y770949D03*
X263174Y855159D03*
Y862887D03*
X251396D03*
Y855159D03*
Y871326D03*
X263174D03*
X262766Y949344D03*
Y967106D03*
Y959859D03*
X262621Y974386D03*
X255086Y959673D03*
Y973752D03*
Y967157D03*
X247590Y959673D03*
Y973752D03*
Y967157D03*
X262621Y990553D03*
Y982114D03*
X254915Y981670D03*
Y997149D03*
Y989113D03*
X247419Y981670D03*
Y997149D03*
Y989113D03*
X254915Y1004668D03*
X247419D03*
X261219Y1124364D03*
Y1134879D03*
X251251Y1124364D03*
Y1134879D03*
X261219Y1145384D03*
X251251D03*
X254978Y1215296D03*
X247482D03*
X254978Y1207777D03*
Y1199741D03*
X247482Y1207777D03*
Y1199741D03*
X259581Y1272430D03*
Y1282945D03*
Y1293450D03*
Y1302787D03*
Y1310515D03*
Y1318954D03*
X263939Y1548010D03*
Y1534139D03*
Y1541055D03*
X261564Y1621823D03*
Y1642843D03*
Y1632338D03*
Y1668347D03*
Y1659908D03*
Y1652180D03*
X248878Y1670386D03*
X265759Y1697613D03*
X254718D03*
X265759Y1676593D03*
Y1687108D03*
X254718D03*
Y1676593D03*
X248707Y1699826D03*
X248878Y1677870D03*
Y1684465D03*
X248707Y1692383D03*
X254457Y1722140D03*
X265498D03*
X265759Y1714678D03*
X254718D03*
Y1706950D03*
X265759D03*
X248707Y1707862D03*
Y1715381D03*
X258639Y1819074D03*
Y1812119D03*
Y1805203D03*
X250468Y1819074D03*
Y1812119D03*
Y1805203D03*
X267396Y1819077D03*
Y1805206D03*
Y1812122D03*
X258459Y1826219D03*
X250288D03*
X267037Y1826222D03*
X258459Y1840090D03*
Y1833135D03*
X267037Y1833138D03*
Y1840093D03*
X250288Y1833135D03*
Y1840090D03*
X245582Y2031480D03*
Y2020965D03*
X258337D03*
Y2031480D03*
X245582Y2041985D03*
Y2051322D03*
Y2059050D03*
X258337Y2051322D03*
Y2059050D03*
Y2041985D03*
Y2067489D03*
X245582D03*
X288102Y54944D03*
Y45572D03*
X271572Y54944D03*
X279754D03*
X271572Y45572D03*
X279754D03*
X288102Y65449D03*
X271572D03*
X279754D03*
X274531Y407289D03*
Y396774D03*
Y417794D03*
X278944Y581440D03*
Y572639D03*
Y601282D03*
Y609010D03*
Y591945D03*
Y617449D03*
X279044Y624627D03*
X274544Y949344D03*
Y967106D03*
Y959859D03*
X274399Y974386D03*
Y990553D03*
Y982114D03*
X279015Y1124077D03*
X288363Y1123935D03*
X279015Y1134592D03*
X288363Y1134450D03*
X269975Y1134735D03*
Y1124220D03*
X288363Y1144955D03*
X279015Y1145097D03*
X269975Y1145240D03*
X286721Y1184312D03*
Y1192040D03*
X278182Y1184455D03*
Y1192183D03*
X286721Y1200479D03*
X278182Y1200622D03*
X270622Y1282945D03*
Y1272430D03*
Y1293450D03*
Y1302787D03*
Y1310515D03*
Y1318954D03*
X278400Y1548190D03*
X271534Y1548010D03*
X285995Y1548190D03*
X278400Y1534319D03*
Y1541235D03*
X271534Y1534139D03*
Y1541055D03*
X285995Y1534319D03*
Y1541235D03*
X273342Y1621823D03*
Y1642843D03*
Y1632338D03*
Y1668347D03*
Y1652180D03*
Y1659908D03*
X270115Y2031480D03*
Y2020965D03*
Y2051322D03*
Y2059050D03*
Y2041985D03*
Y2067489D03*
X300537Y516309D03*
X307966Y516419D03*
Y524147D03*
X300537Y524037D03*
Y532476D03*
X307966Y532586D03*
X292569Y524323D03*
Y516595D03*
Y532762D03*
X315187Y652457D03*
Y661258D03*
X304146D03*
Y652457D03*
Y681100D03*
X315187D03*
Y671763D03*
X304146D03*
X315187Y688828D03*
X304146D03*
Y697267D03*
X315187D03*
X307194Y1020657D03*
X307078Y1007303D03*
X307274Y1001286D03*
X307143Y1014094D03*
X307129Y1027081D03*
X306999Y1033718D03*
X303159Y1184526D03*
Y1192254D03*
X311936Y1192253D03*
Y1184525D03*
X294691Y1184526D03*
Y1192254D03*
X311936Y1200692D03*
X303159Y1200693D03*
X294691D03*
X309823Y1472957D03*
X309464Y1480102D03*
X309823Y1466002D03*
Y1459086D03*
X292715Y1480099D03*
X292895Y1472954D03*
X301066D03*
X300886Y1480099D03*
X292895Y1459083D03*
Y1465999D03*
X301066D03*
Y1459083D03*
X309464Y1493973D03*
Y1487018D03*
X292715Y1487015D03*
Y1493970D03*
X300886D03*
Y1487015D03*
X292754Y1917148D03*
X300349D03*
X292754Y1910232D03*
X300349D03*
X307215Y1910412D03*
X314810D03*
Y1917328D03*
X307215D03*
X292754Y1924103D03*
X300349D03*
X314810Y1924283D03*
X307215D03*
X332775Y318634D03*
X332693Y311980D03*
X332775Y335272D03*
Y342461D03*
Y325935D03*
X332685Y348655D03*
X325139Y516632D03*
Y524360D03*
X316791Y524432D03*
Y516704D03*
Y532871D03*
X325139Y532799D03*
X318235Y1020657D03*
X318315Y1001286D03*
X318119Y1007303D03*
X318184Y1014094D03*
X318170Y1027081D03*
X318040Y1033718D03*
X343816Y318634D03*
X343734Y311980D03*
X343816Y335272D03*
Y342461D03*
Y325935D03*
X343726Y348655D03*
X354391Y1329686D03*
Y1350706D03*
Y1360043D03*
Y1340201D03*
Y1376210D03*
Y1367771D03*
X366169Y1329686D03*
Y1350706D03*
Y1360043D03*
Y1340201D03*
Y1376210D03*
Y1367771D03*
G54D11*
G01X11677Y575962D02*
Y578766D01*
G01X46980Y1335843D02*
X42480D01*
X40151Y1333514D01*
X32250D01*
X28229Y1329493D01*
X12984D01*
X7677Y1334800D01*
Y1337283D01*
G01X16484Y1555159D02*
Y1552159D01*
G01X11085Y1555291D02*
Y1552589D01*
G01X56866Y1336103D02*
Y1330613D01*
X49936Y1323683D01*
Y1310936D01*
X45972Y1306972D01*
Y1301196D01*
X47638Y1299530D01*
X50331D01*
G01X52958Y1336081D02*
X49451D01*
X49213Y1335843D01*
X46980D01*
G01X58750Y577016D02*
Y579653D01*
G01X63820Y577082D02*
Y579654D01*
G01X71909Y1299430D02*
Y1296174D01*
X69377Y1293642D01*
X60873D01*
X58752Y1295763D01*
Y1295869D01*
G01Y1299596D02*
Y1295869D01*
G01D02*
X56527Y1293644D01*
X52131D01*
X50331Y1295444D01*
Y1299530D01*
G01X71866Y1315303D02*
X75475D01*
G01X56866Y1336103D02*
X52980D01*
X52958Y1336081D01*
G01X58130Y1559138D02*
X54108D01*
G01X139920Y78071D02*
X134928Y73079D01*
X115782D01*
X109899Y67196D01*
X99183D01*
X93790Y61803D01*
Y30113D01*
X95583Y28320D01*
X100778D01*
G01Y37438D02*
X97417D01*
G01X100778Y32853D02*
X97417D01*
G01X100518Y381386D02*
X96736D01*
X93159Y377809D01*
Y370244D01*
X94700Y368703D01*
X107306D01*
X117251Y358758D01*
G01X100518Y391220D02*
X97985D01*
G01X100518Y376580D02*
X97536D01*
G01X100518Y371909D02*
X97457D01*
G01X109219Y707246D02*
Y702344D01*
X107839Y700964D01*
Y445787D01*
X87949Y425897D01*
Y413010D01*
X91030Y409929D01*
Y390037D01*
X94882Y386185D01*
X100468D01*
X100518Y386235D01*
G01Y396024D02*
X97643D01*
G01X101056Y725457D02*
X96960D01*
X94533Y723030D01*
Y713178D01*
X100465Y707246D01*
X109219D01*
G01X101056Y730398D02*
X95748D01*
X90612Y735534D01*
Y777207D01*
X111203Y797798D01*
Y1026959D01*
X133837Y1049593D01*
Y1116082D01*
X139920Y1122165D01*
G01X101056Y739962D02*
X97443D01*
G01X101056Y735248D02*
X97534D01*
G01X101189Y1067515D02*
X96904D01*
G01X101189Y1092036D02*
X96948D01*
G01X101189Y1087095D02*
X96949D01*
G01X101189Y1072226D02*
X96774D01*
G01X100227Y1429195D02*
X96386D01*
X93821Y1426630D01*
Y1413029D01*
X108498Y1398352D01*
G01X100227Y1424340D02*
X97403D01*
G01X100227Y1419492D02*
X97825D01*
G01X100227Y1443743D02*
X96993D01*
G01X100227Y1438980D02*
X96996D01*
G01X101677Y1770527D02*
X99269D01*
X93997Y1765255D01*
Y1754470D01*
X113257Y1735210D01*
Y1498837D01*
X116759Y1495335D01*
X123342D01*
X128385Y1490292D01*
Y1481732D01*
X139920Y1470197D01*
G01Y1818228D02*
X125007Y1803315D01*
X115415D01*
X111879Y1806851D01*
X103054D01*
X93810Y1797607D01*
Y1779187D01*
X97483Y1775514D01*
X101677D01*
G01X100778Y28320D02*
Y24288D01*
X100693Y24203D01*
G01X104137Y78186D02*
X104116Y78207D01*
Y82557D01*
G01X119920Y78071D02*
X119853Y78138D01*
X110417D01*
X110389Y78110D01*
X110313Y78186D01*
X107287D01*
G01X117251Y358758D02*
X113119Y354626D01*
Y86983D01*
X116761Y83341D01*
X134550D01*
X139820Y78071D01*
X139920D01*
G01X117251Y358758D02*
X126216D01*
X130978Y363520D01*
Y422771D01*
X134309Y426102D01*
X139920D01*
G01X100518Y386235D02*
Y381386D01*
G01X107668Y426104D02*
X113125D01*
X113142Y426087D01*
X114217D01*
X114232Y426102D01*
X119920D01*
G01X109219Y707246D02*
X145077D01*
X152579Y714748D01*
Y735131D01*
X166214Y748766D01*
Y767185D01*
X163423Y769976D01*
X156332D01*
X155113Y771195D01*
Y776673D01*
G01X101056Y720745D02*
X98591D01*
G01X101056Y715937D02*
X98564D01*
G01X101056Y730398D02*
Y725457D01*
G01X107592Y774100D02*
X107596Y774104D01*
X114655D01*
X114685Y774134D01*
X119920D01*
G01Y1122165D02*
X111235D01*
X111234Y1122166D01*
X108834D01*
G01X105684D02*
Y1125919D01*
G01X108498Y1398352D02*
Y1226062D01*
X114592Y1219968D01*
Y1130649D01*
X118155Y1127086D01*
X134999D01*
X139920Y1122165D01*
G01Y1470197D02*
X131851Y1462128D01*
Y1405479D01*
X124724Y1398352D01*
X108498D01*
G01X100227Y1434041D02*
Y1429195D01*
G01X119920Y1470197D02*
X110948D01*
X110940Y1470205D01*
X108540D01*
G01X105455Y1472894D02*
Y1470270D01*
X105390Y1470205D01*
G01X101677Y1760827D02*
X99068D01*
G01X101677Y1765722D02*
X99103D01*
G01X101677Y1770527D02*
Y1775514D01*
G01Y1785571D02*
X99047D01*
G01X101677Y1780542D02*
X98873D01*
G01X155202Y72497D02*
X145494D01*
X139920Y78071D01*
G01Y88071D02*
X155270D01*
X155366Y88167D01*
G01X156321Y418198D02*
X147824D01*
X139920Y426102D01*
G01X155113Y776673D02*
X142459D01*
X139920Y774134D01*
G01Y784134D02*
X155354D01*
X155356Y784132D01*
G01X156117Y1116127D02*
X145958D01*
X139920Y1122165D01*
G01Y1132165D02*
X155334D01*
X155347Y1132178D01*
G01X155648Y1473020D02*
X142743D01*
X139920Y1470197D01*
G01X155409Y1820360D02*
X142052D01*
X139920Y1818228D01*
G01Y1828228D02*
X155653D01*
X155656Y1828225D01*
G01X158352Y72497D02*
X161742D01*
G01X158463Y68130D02*
X162586D01*
G01X162384Y56744D02*
X159676D01*
G01X161257Y420869D02*
Y418194D01*
X161256Y418195D01*
G01X161377Y407575D02*
X158490D01*
G01X161826Y756757D02*
X158950D01*
G01X158665Y764231D02*
X161644D01*
G01X158263Y776673D02*
X159336D01*
X161131Y774878D01*
G01X159278Y1106853D02*
X162140D01*
G01X164539Y1116135D02*
X160870D01*
G01X163099Y1457084D02*
Y1457069D01*
X160252Y1457084D01*
G01X159505Y1462651D02*
X162524D01*
G01X158798Y1473020D02*
X160602D01*
X162242Y1471380D01*
G01X162140Y1807740D02*
X158840D01*
G01X158563Y1815631D02*
X163250Y1815650D01*
Y1815631D01*
G01X184284Y943579D02*
Y948331D01*
G01X184196Y962671D02*
Y967371D01*
G01X184632Y979154D02*
Y983423D01*
G01X184353Y996558D02*
Y1001556D01*
G01X184118Y1015313D02*
Y1019280D01*
G01X182329Y1025022D02*
X184173D01*
X188385Y1020810D01*
G01X287420Y166264D02*
Y162540D01*
G01X283086Y166264D02*
Y162675D01*
G01X271547Y241764D02*
Y245353D01*
G01X281193Y238439D02*
Y241624D01*
G01X276617Y238439D02*
Y241400D01*
G01X285513Y341517D02*
Y337688D01*
G01X281074Y341517D02*
Y337688D01*
G01X289895Y341517D02*
Y337688D01*
G01X281569Y417340D02*
Y421169D01*
G01X286665Y414015D02*
Y417844D01*
G01X291002Y414015D02*
Y417844D01*
G01X282776Y515919D02*
Y512341D01*
G01X278405Y515919D02*
Y512341D01*
G01X273938Y515919D02*
Y512341D01*
G01X269516Y515919D02*
Y512341D01*
G01X285348Y591962D02*
Y595540D01*
G01X290984Y588637D02*
Y592215D01*
G01X274514Y691124D02*
Y687192D01*
G01X270109Y691124D02*
Y687192D01*
G01X283340Y691124D02*
Y687192D01*
G01X278955Y691124D02*
Y687192D01*
G01X273114Y767036D02*
Y770968D01*
G01X278184Y763711D02*
Y767643D01*
G01X282737Y763711D02*
Y767643D01*
G01X285788Y866243D02*
Y862237D01*
G01X281305Y866243D02*
Y862237D01*
G01X276686Y866243D02*
Y862488D01*
G01X272181Y866243D02*
Y862354D01*
G01X275966Y940761D02*
Y944767D01*
G01X281194Y937436D02*
Y941442D01*
G01X285874Y937436D02*
Y941442D01*
G01X285666Y1034882D02*
Y1031162D01*
G01X281124Y1034882D02*
Y1031162D01*
G01X290107Y1034882D02*
Y1031162D01*
G01X282958Y1115751D02*
Y1119471D01*
G01X288188Y1112426D02*
Y1116146D01*
G01X289082Y1210314D02*
Y1206777D01*
G01X284194Y1210314D02*
Y1206777D01*
G01X279559Y1210314D02*
Y1206777D01*
G01X289210Y1287097D02*
Y1290634D01*
G01X283808Y1290422D02*
Y1293959D01*
G01X284240Y1393342D02*
Y1389544D01*
G01X279518Y1393341D02*
Y1389543D01*
G01X275052Y1393341D02*
Y1389715D01*
G01X270579Y1393341D02*
Y1389626D01*
G01X270234Y1463962D02*
Y1467760D01*
G01X275521Y1460637D02*
Y1464435D01*
G01X279990Y1460637D02*
Y1464435D01*
G01X289675Y1562451D02*
Y1558211D01*
G01X285054Y1562451D02*
Y1558211D01*
G01X284086Y1640643D02*
Y1644883D01*
G01X289421Y1637318D02*
Y1641558D01*
G01X274704Y1741915D02*
Y1738196D01*
G01X279703Y1741915D02*
Y1738398D01*
G01X284583Y1741915D02*
Y1738465D01*
G01X289499Y1741915D02*
Y1738735D01*
G01X281066Y1814871D02*
Y1819569D01*
G01X286623Y1811546D02*
Y1814400D01*
G01X288794Y1858668D02*
X293606D01*
G01X287121Y1916895D02*
Y1913327D01*
G01X282717Y1916895D02*
Y1913327D01*
G01X278262Y1916895D02*
Y1913327D01*
G01X273817Y1916895D02*
Y1913327D01*
G01X299687Y60393D02*
Y63778D01*
G01X304151Y60393D02*
Y63778D01*
G01X308651Y60393D02*
Y63778D01*
G01X313089Y60393D02*
Y63778D01*
G01X294483Y63718D02*
Y67732D01*
G01X291943Y166264D02*
Y162630D01*
G01X296523Y166264D02*
Y162585D01*
G01X294506Y341517D02*
Y337688D01*
G01X295509Y588637D02*
Y592215D01*
G01X294617Y1034882D02*
Y1031162D01*
G01X292698Y1112426D02*
Y1116146D01*
G01X293807Y1210314D02*
Y1206777D01*
G01X294133Y1287097D02*
Y1290634D01*
G01X308636Y1513883D02*
X313894D01*
G01X298870Y1562451D02*
Y1558211D01*
G01X294392Y1562451D02*
Y1558211D01*
G01X294090Y1637318D02*
Y1641558D01*
G01X291550Y1811546D02*
Y1814846D01*
G01X314562Y1989407D02*
Y1994087D01*
G01X322005Y60393D02*
Y63778D01*
G01X317567Y60393D02*
Y63778D01*
G01X320208Y1162266D02*
X325796D01*
G01X324803Y1987031D02*
Y1990272D01*
G01X320045Y1987031D02*
Y1990215D01*
X25219Y18752D03*
X3001Y52034D03*
Y100034D03*
Y150034D03*
Y200034D03*
Y250034D03*
Y300034D03*
Y350034D03*
Y400034D03*
Y450034D03*
Y500034D03*
Y550034D03*
X11677Y578766D03*
X3001Y600034D03*
Y650034D03*
Y700034D03*
Y750034D03*
Y800034D03*
Y850034D03*
Y900034D03*
Y950034D03*
Y1000034D03*
Y1050034D03*
Y1100034D03*
Y1150034D03*
Y1200034D03*
Y1250034D03*
Y1300034D03*
Y1350034D03*
Y1400034D03*
Y1450034D03*
Y1500034D03*
Y1550034D03*
X16484Y1552159D03*
X11085Y1552589D03*
X3006Y1594602D03*
X3012Y1610165D03*
X3001Y1650034D03*
Y1700034D03*
Y1750034D03*
Y1800034D03*
Y1850034D03*
Y1900034D03*
Y1950034D03*
Y2000034D03*
Y2050034D03*
X48433Y866179D03*
X48467Y869278D03*
X49441Y1238962D03*
X46980Y1335843D03*
Y1325843D03*
Y1315843D03*
Y1320843D03*
Y1330843D03*
Y1345843D03*
Y1340843D03*
X26833Y2067866D03*
X58750Y579653D03*
X63820Y579654D03*
X61888Y666012D03*
X57124Y675327D03*
X54483Y679810D03*
X59236Y670758D03*
X70865Y854278D03*
Y872278D03*
Y866278D03*
Y860278D03*
Y897750D03*
Y890116D03*
X60815Y1019026D03*
X63577Y1019115D03*
X59127Y1257647D03*
X57458Y1253378D03*
X58356Y1279812D03*
X58416Y1272383D03*
X54543Y1296513D03*
X63061Y1296312D03*
X67568Y1296654D03*
X61866Y1309190D03*
X67568Y1307829D03*
X54543Y1308995D03*
X61866Y1342104D03*
X54108Y1559138D03*
X75219Y18752D03*
X97417Y32853D03*
Y37438D03*
X97536Y376580D03*
X97457Y371909D03*
X97985Y391220D03*
X97643Y396024D03*
X93223Y417736D03*
X94347Y421562D03*
X98591Y720745D03*
X98564Y715937D03*
X97443Y739962D03*
X97534Y735248D03*
X98124Y745139D03*
X95775Y751469D03*
X92216Y899865D03*
X90708Y878615D03*
X92633Y907404D03*
X92989Y927334D03*
X98139Y990959D03*
X76446Y1014871D03*
X79499D03*
X96904Y1067515D03*
X82763Y1060051D03*
X96948Y1092036D03*
X96949Y1087095D03*
X96774Y1072226D03*
X96684Y1081791D03*
X75475Y1315303D03*
X96510Y1395382D03*
X97403Y1424340D03*
X97825Y1419492D03*
X96993Y1443743D03*
X96996Y1438980D03*
X97465Y1447919D03*
X95236Y1453321D03*
X76833Y2067866D03*
X106335Y22580D03*
X106958Y26285D03*
X108082Y38899D03*
X102646Y49461D03*
X101430Y41803D03*
X107405Y49898D03*
X107037Y34687D03*
X104350Y62293D03*
X107263Y72244D03*
X109054Y58250D03*
X104116Y82557D03*
X107213Y85169D03*
X106836Y376461D03*
X106709Y391219D03*
X105451Y406795D03*
X114498Y396207D03*
X101990Y426104D03*
X109475Y434743D03*
X111017Y419566D03*
X107025Y725368D03*
X105087Y754126D03*
X106935Y745139D03*
X107173Y735219D03*
X101244Y774100D03*
X112836Y769122D03*
X113697Y794293D03*
X105395Y972040D03*
X102611Y972220D03*
X100687Y999391D03*
X107351Y1093484D03*
X107235Y1081791D03*
X107215Y1072208D03*
X98652Y1096403D03*
X108779Y1105760D03*
X105152Y1118381D03*
X112503Y1115860D03*
X105684Y1125919D03*
X108468Y1129286D03*
X100719Y1312810D03*
Y1306810D03*
Y1330810D03*
Y1336810D03*
Y1324810D03*
Y1318810D03*
Y1346065D03*
X101626Y1397635D03*
X106962Y1434041D03*
X106921Y1419492D03*
X106763Y1444599D03*
X107006Y1452651D03*
X105455Y1472894D03*
X108574Y1463389D03*
X113518Y1489571D03*
X99103Y1765722D03*
X99068Y1760827D03*
X107355Y1770437D03*
X99047Y1785571D03*
X98873Y1780542D03*
X99294Y1789947D03*
X107391Y1794460D03*
X107220Y1791589D03*
X107373Y1780544D03*
X105669Y1815227D03*
X108819Y1812118D03*
X106819Y1802230D03*
X108819Y1824470D03*
X109991Y2083607D03*
X125219Y3002D03*
X144878Y1738861D03*
X162384Y56744D03*
X157558Y51426D03*
X161742Y72497D03*
X162586Y68130D03*
X161339Y88108D03*
X159417Y91281D03*
X158901Y85017D03*
X161377Y407575D03*
X156865Y401207D03*
X161517Y436119D03*
X161257Y420869D03*
X159019Y439268D03*
X158807Y432969D03*
X156610Y751063D03*
X161826Y756757D03*
X161131Y774878D03*
X161644Y764231D03*
X158956Y780982D03*
X161479Y784141D03*
X159053Y787280D03*
X164539Y1116135D03*
X162140Y1106853D03*
X156854Y1101031D03*
X159382Y1136151D03*
X158456Y1129045D03*
X158618Y1399448D03*
X164037Y1400226D03*
X170351Y1401324D03*
X159192Y1451105D03*
X163099Y1457084D03*
X162524Y1462651D03*
X162242Y1471380D03*
X159216Y1477124D03*
X159526Y1483434D03*
X150309Y1737009D03*
X168151Y1739208D03*
X156183Y1735240D03*
X165782Y1732903D03*
X163257Y1737619D03*
X163250Y1815631D03*
X162140Y1807740D03*
X156452Y1800821D03*
X161844Y1828225D03*
X159822Y1831380D03*
X159075Y1825087D03*
X159991Y2083607D03*
X175219Y3002D03*
X184284Y948331D03*
X175989Y944537D03*
X176011Y936829D03*
X184196Y967371D03*
X175359Y963486D03*
X175561Y955964D03*
X175135Y972490D03*
X184632Y983423D03*
X175022Y980281D03*
X175742Y989958D03*
X175449Y997660D03*
X184353Y1001556D03*
X184118Y1019280D03*
X188385Y1020810D03*
X175698Y1008730D03*
X175473Y1016296D03*
X175448Y1031766D03*
X175897Y1023997D03*
X176083Y1402321D03*
X173394Y1736051D03*
X209991Y2083607D03*
X225219Y3002D03*
X267627Y115559D03*
X256947Y128276D03*
X257125Y115559D03*
X265722Y463102D03*
X265737Y473680D03*
X255837Y823626D03*
X255687Y812192D03*
X259991Y2083607D03*
X275219Y3002D03*
X287420Y162540D03*
X283086Y162675D03*
X271547Y245353D03*
X276617Y241400D03*
X281193Y241624D03*
X285513Y337688D03*
X281074D03*
X289895D03*
X286665Y417844D03*
X291002D03*
X281569Y421169D03*
X274991Y463099D03*
X282776Y512341D03*
X278405D03*
X273938D03*
X269516D03*
X285348Y595540D03*
X290984Y592215D03*
X274514Y687192D03*
X270109D03*
X283340D03*
X278955D03*
X273114Y770968D03*
X278184Y767643D03*
X282737D03*
X270070Y812192D03*
X276686Y862488D03*
X272181Y862354D03*
X285788Y862237D03*
X281305D03*
X275966Y944767D03*
X281194Y941442D03*
X285874D03*
X285666Y1031162D03*
X281124D03*
X290107D03*
X282958Y1119471D03*
X288188Y1116146D03*
X289082Y1206777D03*
X284194D03*
X279559D03*
X283808Y1293959D03*
X289210Y1290634D03*
X284240Y1389544D03*
X279518Y1389543D03*
X275052Y1389715D03*
X270579Y1389626D03*
X270234Y1467760D03*
X275521Y1464435D03*
X279990D03*
X289675Y1558211D03*
X285054D03*
X284086Y1644883D03*
X289421Y1641558D03*
X274704Y1738196D03*
X279703Y1738398D03*
X284583Y1738465D03*
X289499Y1738735D03*
X281066Y1819569D03*
X291550Y1814846D03*
X286623Y1814400D03*
X280240Y1858668D03*
X279976Y1864565D03*
X287121Y1913327D03*
X282717D03*
X278262D03*
X273817D03*
X299687Y63778D03*
X304151D03*
X308651D03*
X313089D03*
X294483Y67732D03*
X296523Y162585D03*
X291943Y162630D03*
X308057Y248863D03*
X306267Y241010D03*
X314914Y238162D03*
X314940Y252083D03*
X305867Y258589D03*
X294506Y337688D03*
X295509Y592215D03*
X294617Y1031162D03*
X309678Y1053262D03*
X292698Y1116146D03*
X312527Y1162266D03*
X312698Y1172804D03*
X293807Y1206777D03*
X294133Y1290634D03*
X314183Y1403423D03*
X313894Y1513883D03*
X302267Y1524401D03*
X301734Y1513883D03*
X312077Y1575871D03*
X298870Y1558211D03*
X294392D03*
X294090Y1641558D03*
X311539Y1753499D03*
X292614Y1864565D03*
X293606Y1858668D03*
X314562Y1994087D03*
X309991Y2083607D03*
X325219Y3002D03*
X331403Y51409D03*
X333889Y56021D03*
X338227Y61559D03*
X322005Y63778D03*
X317567D03*
X320372Y225979D03*
X318088Y231820D03*
X321899Y238137D03*
X329930Y245684D03*
X331046Y232021D03*
X320961Y250105D03*
X324709Y231580D03*
X335522Y404033D03*
X323313Y418313D03*
X326196Y413982D03*
X328950Y409216D03*
X320980Y423225D03*
X336617Y577978D03*
X319305Y582111D03*
X329636Y584715D03*
X317724Y588250D03*
X337387Y586230D03*
X320380Y576491D03*
X331867Y589810D03*
X333750Y595326D03*
X323751Y589155D03*
X319852Y593330D03*
X321742Y599041D03*
X331568Y752967D03*
X339012Y752859D03*
X329336Y762693D03*
X334010Y758588D03*
X327524Y758020D03*
X339615Y926357D03*
X329938Y948756D03*
X332527Y943746D03*
X324098Y946104D03*
X318557Y941178D03*
X323868Y929978D03*
X326646Y939788D03*
X333300Y928464D03*
X336160Y937262D03*
X328583Y933262D03*
X321425Y951577D03*
X324246Y1051786D03*
X335677Y1048904D03*
X317592Y1053050D03*
X331920Y1116088D03*
X337509Y1109598D03*
X328989Y1121090D03*
X326558Y1126368D03*
X325796Y1162266D03*
X323403Y1172804D03*
X327452Y1279447D03*
X321978Y1282086D03*
X338047Y1282599D03*
X333242Y1276809D03*
X329619Y1284016D03*
X327932Y1289221D03*
X319404Y1401346D03*
X325636Y1399114D03*
X334646Y1400804D03*
X323720Y1570924D03*
X329399Y1571939D03*
X317243Y1574832D03*
X333474Y1566686D03*
X335963Y1573797D03*
X329887Y1752081D03*
X321283Y1753466D03*
X335730Y1753270D03*
X338309Y1927623D03*
X332399Y1926787D03*
X324803Y1990272D03*
X320045Y1990215D03*
X359931Y52189D03*
X348289Y50863D03*
X345089Y56190D03*
X340373Y51579D03*
X342097Y401684D03*
X363825Y401768D03*
X342900Y580126D03*
X362577Y752783D03*
X344109Y751809D03*
X343656Y933725D03*
X345578Y1047844D03*
X344099Y1106798D03*
X349855Y1104302D03*
X344130Y1401670D03*
X350690Y1403243D03*
X348710Y1570187D03*
X361011Y1568890D03*
X343402Y1572080D03*
X348245Y1575241D03*
X355364Y1570990D03*
X345537Y1916558D03*
X344402Y1911123D03*
X363361Y1918313D03*
X358318Y1920680D03*
X363411Y1923459D03*
X340336Y1922409D03*
X347676Y1922165D03*
X359991Y2083607D03*
X375219Y3002D03*
X372204Y56126D03*
X365720Y52336D03*
X379257Y52158D03*
X379572Y58441D03*
X387524Y76847D03*
X374442Y406857D03*
X380619Y410112D03*
X380878Y403999D03*
X374542Y401282D03*
X368907Y404308D03*
X376654Y754748D03*
X382892Y767710D03*
X386790Y774338D03*
X380186Y761742D03*
X379335Y1189778D03*
X383276Y1184136D03*
X386816Y1179841D03*
X376472Y1194999D03*
X373674Y1199967D03*
X371523Y1204725D03*
X367829Y1566108D03*
X374775Y1919243D03*
X379403Y1917261D03*
X369748Y1921795D03*
X402512Y17108D03*
Y67108D03*
Y117108D03*
Y167108D03*
Y217108D03*
Y267108D03*
Y317108D03*
Y367108D03*
Y417108D03*
Y467108D03*
Y517108D03*
Y567108D03*
Y617108D03*
Y667108D03*
Y717108D03*
Y767108D03*
X391278Y765894D03*
X402512Y817108D03*
Y867108D03*
Y917108D03*
Y967108D03*
Y1017108D03*
Y1067108D03*
Y1117108D03*
Y1167108D03*
Y1217108D03*
Y1267108D03*
Y1317108D03*
Y1367108D03*
Y1417108D03*
Y1467108D03*
Y1517108D03*
Y1567108D03*
Y1617108D03*
Y1667108D03*
Y1717108D03*
Y1767108D03*
Y1817108D03*
Y1867108D03*
Y1917108D03*
Y1967108D03*
Y2017108D03*
Y2067108D03*
G54D30*
X71866Y1315303D03*
X66866D03*
X61866D03*
X56866D03*
Y1336103D03*
X61866D03*
X66866D03*
X71866D03*
G54D12*
X12735Y59953D03*
Y181976D03*
Y268811D03*
Y390834D03*
Y1922291D03*
Y2026661D03*
X57735Y59953D03*
Y181976D03*
Y268811D03*
Y390834D03*
Y1922291D03*
Y2026661D03*
G54D21*
X20468Y696341D03*
Y984333D03*
X20472Y1054606D03*
Y1342598D03*
G54D40*
G01X54413Y1253378D02*
X57458D01*
G01X54543Y1299531D02*
Y1296513D01*
G01X63061Y1299596D02*
Y1296312D01*
G01X67568Y1299431D02*
Y1296654D01*
G01X101189Y1081791D02*
X96684D01*
G01X100293Y1447919D02*
X97465D01*
G01X105845Y20080D02*
Y22090D01*
X106335Y22580D01*
G01X105845Y15847D02*
Y20080D01*
G01X108082Y41803D02*
Y38899D01*
G01X104940Y46285D02*
Y47167D01*
X102646Y49461D01*
G01X102727Y58250D02*
Y60670D01*
X104350Y62293D01*
G01X107213Y85169D02*
Y85224D01*
X107268Y85169D01*
Y81355D01*
G01X104518Y426104D02*
X101990D01*
G01X109475Y434743D02*
X107668Y432936D01*
Y429254D01*
G01X111017Y419566D02*
X107668Y422915D01*
Y422954D01*
G01X101196Y745139D02*
X98124D01*
G01X104442Y774100D02*
X101244D01*
G01X113697Y794293D02*
Y783381D01*
X107615Y777299D01*
G01X107617Y771001D02*
X110957D01*
X112836Y769122D01*
G01X101189Y1081791D02*
Y1076901D01*
G01X101282Y1096403D02*
X98652D01*
G01X108819Y1119015D02*
X109348D01*
X112503Y1115860D01*
G01X108468Y1129286D02*
X108816Y1128938D01*
Y1125313D01*
G01X108573Y1473357D02*
Y1484626D01*
X113518Y1489571D01*
G01X108574Y1467057D02*
Y1463389D01*
G01X101780Y1789947D02*
X99294D01*
G01X119920Y1818228D02*
X108819D01*
G01X105669D02*
Y1815227D01*
G01X108819Y1815078D02*
Y1812118D01*
G01Y1821378D02*
Y1824470D01*
G01X139920Y436102D02*
X155331D01*
X155348Y436119D01*
G01X158559Y88108D02*
X161339D01*
G01X155370Y91281D02*
X159417D01*
G01X155366Y85017D02*
X158901D01*
G01X158498Y436119D02*
X161517D01*
G01X155351Y439268D02*
X159019D01*
G01X155348Y432969D02*
X158807D01*
G01X155356Y780982D02*
X158956D01*
G01X158519Y784141D02*
X161479D01*
G01X159053Y787280D02*
X155362D01*
G01X155264Y1135344D02*
X156071Y1136151D01*
X159382D01*
G01X155263Y1129045D02*
X158456D01*
G01X155816Y1477124D02*
X159216D01*
G01X155834Y1483424D02*
X159526Y1483434D01*
G01X158806Y1828225D02*
X161844D01*
G01X155570Y1831380D02*
X159822D01*
G01X155561Y1825087D02*
X159075D01*
G01X175989Y944537D02*
X176947Y943579D01*
X181134D01*
G01X176011Y936829D02*
X177161Y937979D01*
X181223D01*
G01X175359Y963486D02*
X176174Y962671D01*
X181046D01*
G01X175561Y955964D02*
X176668Y957071D01*
X181135D01*
G01X175135Y972490D02*
X176199Y973554D01*
X181389D01*
G01X175022Y980281D02*
X176149Y979154D01*
X181482D01*
G01X175742Y989958D02*
X176742Y990958D01*
X181247D01*
G01X175449Y997660D02*
Y997636D01*
X176527Y996558D01*
X181203D01*
G01X175698Y1008730D02*
X176681Y1009713D01*
X180965D01*
G01X180968Y1015313D02*
X176456D01*
X175473Y1016296D01*
G01X179177Y1030622D02*
X176649D01*
X176624Y1030597D01*
Y1030590D01*
X175448Y1031766D01*
G01X179179Y1025022D02*
X176922D01*
X175897Y1023997D01*
G01X264929Y115559D02*
X267627D01*
G01X261535Y128228D02*
X258975D01*
X258927Y128276D01*
X256947D01*
G01X261779Y115559D02*
X257125D01*
G01X265722Y463102D02*
X268958D01*
X268961Y463099D01*
G01X265737Y473680D02*
X268885D01*
X268888Y473677D01*
G01X264335Y812170D02*
X270048D01*
X270070Y812192D01*
G01X255837Y823626D02*
X261003D01*
X261025Y823604D01*
G01X255687Y812192D02*
X261163D01*
X261185Y812170D01*
G01X272111Y463099D02*
X274991D01*
G01X288712Y1864565D02*
X292614D01*
G01X285644Y1858668D02*
X280240D01*
G01X285562Y1864565D02*
X279976D01*
G01X317058Y1162266D02*
X312527D01*
G01X317114Y1172804D02*
X312698D01*
G01X305756Y1524401D02*
X302267D01*
G01X305486Y1513883D02*
X301734D01*
G01X320264Y1172804D02*
X323403D01*
G54D13*
X17735Y206976D03*
Y415834D03*
Y1947291D03*
Y2051661D03*
X52735Y34953D03*
Y243811D03*
X203542Y73105D03*
X204069Y152050D03*
X204137Y247568D03*
X204597Y331786D03*
X203541Y421732D03*
X204333Y506517D03*
X206668Y598130D03*
X204596Y681645D03*
X205626Y774526D03*
X205386Y856244D03*
X210091Y947202D03*
X209296Y1032544D03*
X205030Y1122856D03*
X205122Y1206233D03*
X205626Y1299104D03*
X204332Y1380966D03*
X203243Y1474162D03*
X204859Y1557277D03*
X205923Y1648177D03*
X205387Y1731351D03*
X205310Y1823227D03*
X204069Y1900420D03*
X205905Y1998730D03*
X205310Y2043388D03*
G54D22*
X25389Y1030199D03*
X25393Y1388464D03*
G54D31*
X119920Y18071D03*
Y28071D03*
Y38071D03*
Y48071D03*
Y58071D03*
Y68071D03*
Y78071D03*
Y88071D03*
Y98071D03*
Y108071D03*
Y118071D03*
Y128071D03*
Y138071D03*
Y148071D03*
Y158071D03*
Y168071D03*
Y178071D03*
Y188071D03*
Y198071D03*
Y208071D03*
Y218071D03*
Y228071D03*
Y238071D03*
Y248071D03*
Y258071D03*
Y268071D03*
Y278071D03*
Y288071D03*
Y298071D03*
Y308071D03*
Y318071D03*
Y366102D03*
Y376102D03*
Y386102D03*
Y396102D03*
Y406102D03*
Y416102D03*
Y426102D03*
Y436102D03*
Y446102D03*
Y456102D03*
Y466102D03*
Y476102D03*
Y486102D03*
Y496102D03*
Y506102D03*
Y516102D03*
Y526102D03*
Y536102D03*
Y546102D03*
Y556102D03*
Y566102D03*
Y576102D03*
Y586102D03*
Y596102D03*
Y606102D03*
Y616102D03*
Y626102D03*
Y636102D03*
Y646102D03*
Y656102D03*
Y666102D03*
Y714134D03*
Y724134D03*
Y734134D03*
Y744134D03*
Y754134D03*
Y764134D03*
Y774134D03*
Y784134D03*
Y794134D03*
Y804134D03*
Y814134D03*
Y824134D03*
Y834134D03*
Y844134D03*
Y854134D03*
Y864134D03*
Y874134D03*
Y884134D03*
Y894134D03*
Y904134D03*
Y914134D03*
Y924134D03*
Y934134D03*
Y944134D03*
Y954134D03*
Y964134D03*
Y974134D03*
Y984134D03*
Y994134D03*
Y1004134D03*
Y1014134D03*
Y1062165D03*
Y1072165D03*
Y1082165D03*
Y1092165D03*
Y1102165D03*
Y1112165D03*
Y1122165D03*
Y1132165D03*
Y1142165D03*
Y1152165D03*
Y1162165D03*
Y1172165D03*
Y1182165D03*
Y1192165D03*
Y1202165D03*
Y1212165D03*
Y1222165D03*
Y1232165D03*
Y1242165D03*
Y1252165D03*
Y1262165D03*
Y1272165D03*
Y1282165D03*
Y1292165D03*
Y1302165D03*
Y1312165D03*
Y1322165D03*
Y1332165D03*
Y1342165D03*
Y1352165D03*
Y1362165D03*
Y1410197D03*
Y1420197D03*
Y1430197D03*
Y1440197D03*
Y1450197D03*
Y1460197D03*
Y1470197D03*
Y1480197D03*
Y1490197D03*
Y1500197D03*
Y1510197D03*
Y1520197D03*
Y1530197D03*
Y1540197D03*
Y1550197D03*
Y1560197D03*
Y1570197D03*
Y1580197D03*
Y1590197D03*
Y1600197D03*
Y1610197D03*
Y1620197D03*
Y1630197D03*
Y1640197D03*
Y1650197D03*
Y1660197D03*
Y1670197D03*
Y1680197D03*
Y1690197D03*
Y1700197D03*
Y1710197D03*
Y1758228D03*
Y1768228D03*
Y1778228D03*
Y1788228D03*
Y1798228D03*
Y1808228D03*
Y1818228D03*
Y1828228D03*
Y1838228D03*
Y1848228D03*
Y1858228D03*
Y1868228D03*
Y1878228D03*
Y1888228D03*
Y1898228D03*
Y1908228D03*
Y1918228D03*
Y1928228D03*
Y1938228D03*
Y1948228D03*
Y1958228D03*
Y1968228D03*
Y1978228D03*
Y1988228D03*
Y1998228D03*
Y2008228D03*
Y2018228D03*
Y2028228D03*
Y2038228D03*
Y2048228D03*
Y2058228D03*
X139920Y28071D03*
Y18071D03*
Y58071D03*
Y48071D03*
Y38071D03*
Y78071D03*
Y68071D03*
Y98071D03*
Y88071D03*
Y128071D03*
Y118071D03*
Y108071D03*
Y148071D03*
Y138071D03*
Y178071D03*
Y168071D03*
Y158071D03*
Y198071D03*
Y188071D03*
Y228071D03*
Y218071D03*
Y208071D03*
Y248071D03*
Y238071D03*
Y268071D03*
Y258071D03*
Y298071D03*
Y288071D03*
Y278071D03*
Y318071D03*
Y308071D03*
Y328071D03*
Y366102D03*
Y396102D03*
Y386102D03*
Y376102D03*
Y416102D03*
Y406102D03*
Y436102D03*
Y426102D03*
Y466102D03*
Y456102D03*
Y446102D03*
Y486102D03*
Y476102D03*
Y516102D03*
Y506102D03*
Y496102D03*
Y536102D03*
Y526102D03*
Y566102D03*
Y556102D03*
Y546102D03*
Y586102D03*
Y576102D03*
Y606102D03*
Y596102D03*
Y636102D03*
Y626102D03*
Y616102D03*
Y656102D03*
Y646102D03*
Y676102D03*
Y666102D03*
Y734134D03*
Y724134D03*
Y714134D03*
Y754134D03*
Y744134D03*
Y774134D03*
Y764134D03*
Y804134D03*
Y794134D03*
Y784134D03*
Y824134D03*
Y814134D03*
Y854134D03*
Y844134D03*
Y834134D03*
Y874134D03*
Y864134D03*
Y904134D03*
Y894134D03*
Y884134D03*
Y924134D03*
Y914134D03*
Y944134D03*
Y934134D03*
Y974134D03*
Y964134D03*
Y954134D03*
Y994134D03*
Y984134D03*
Y1024134D03*
Y1014134D03*
Y1004134D03*
Y1072165D03*
Y1062165D03*
Y1092165D03*
Y1082165D03*
Y1122165D03*
Y1112165D03*
Y1102165D03*
Y1142165D03*
Y1132165D03*
Y1162165D03*
Y1152165D03*
Y1192165D03*
Y1182165D03*
Y1172165D03*
Y1212165D03*
Y1202165D03*
Y1242165D03*
Y1232165D03*
Y1222165D03*
Y1262165D03*
Y1252165D03*
Y1282165D03*
Y1272165D03*
Y1312165D03*
Y1302165D03*
Y1292165D03*
Y1332165D03*
Y1322165D03*
Y1362165D03*
Y1352165D03*
Y1342165D03*
Y1372165D03*
Y1410197D03*
Y1430197D03*
Y1420197D03*
Y1460197D03*
Y1450197D03*
Y1440197D03*
Y1480197D03*
Y1470197D03*
Y1500197D03*
Y1490197D03*
Y1530197D03*
Y1520197D03*
Y1510197D03*
Y1550197D03*
Y1540197D03*
Y1580197D03*
Y1570197D03*
Y1560197D03*
Y1600197D03*
Y1590197D03*
Y1620197D03*
Y1610197D03*
Y1650197D03*
Y1640197D03*
Y1630197D03*
Y1670197D03*
Y1660197D03*
Y1700197D03*
Y1690197D03*
Y1680197D03*
Y1720197D03*
Y1710197D03*
Y1768228D03*
Y1758228D03*
Y1798228D03*
Y1788228D03*
Y1778228D03*
Y1818228D03*
Y1808228D03*
Y1838228D03*
Y1828228D03*
Y1868228D03*
Y1858228D03*
Y1848228D03*
Y1888228D03*
Y1878228D03*
Y1918228D03*
Y1908228D03*
Y1898228D03*
Y1938228D03*
Y1928228D03*
Y1958228D03*
Y1948228D03*
Y1988228D03*
Y1978228D03*
Y1968228D03*
Y2008228D03*
Y1998228D03*
Y2038228D03*
Y2028228D03*
Y2018228D03*
Y2058228D03*
Y2048228D03*
Y2068228D03*
G54D41*
G01X-723776Y2987387D02*
Y-376795D01*
Y-489221D01*
X1782976D01*
Y-376795D01*
Y2987387D01*
X-723776D01*
G01X-4000Y-62500D02*
Y-137500D01*
X496000D01*
Y-62500D01*
X-4000D01*
G01X8000Y-127500D02*
Y-132500D01*
G01X6543Y-127500D02*
X9457D01*
G01X14367Y-132500D02*
X11833D01*
Y-127500D01*
X14367D01*
G01X13353Y-129917D02*
X11833D01*
G01X16933Y-127500D02*
Y-132500D01*
X19467D01*
G01X23300Y-132667D02*
X23173Y-132583D01*
Y-132417D01*
X23300Y-132333D01*
X23427Y-132417D01*
Y-132583D01*
X23300Y-132667D01*
G01Y-130417D02*
X23173Y-130333D01*
Y-130167D01*
X23300Y-130083D01*
X23427Y-130167D01*
Y-130333D01*
X23300Y-130417D01*
G01X28083Y-134167D02*
X27450Y-133333D01*
X27133Y-132500D01*
Y-129167D01*
X27450Y-128333D01*
X28083Y-127500D01*
G01X33500D02*
X32993Y-127667D01*
X32613Y-128083D01*
X32360Y-128583D01*
X32170Y-129250D01*
X32107Y-130000D01*
X32170Y-130750D01*
X32360Y-131417D01*
X32613Y-131917D01*
X32993Y-132333D01*
X33500Y-132500D01*
X34007Y-132333D01*
X34387Y-131917D01*
X34640Y-131417D01*
X34830Y-130750D01*
X34893Y-130000D01*
X34830Y-129250D01*
X34640Y-128583D01*
X34387Y-128083D01*
X34007Y-127667D01*
X33500Y-127500D01*
G01X37207Y-131500D02*
X37587Y-132083D01*
X38093Y-132417D01*
X38663Y-132500D01*
X39170Y-132417D01*
X39677Y-132000D01*
X39993Y-131500D01*
X40057Y-131000D01*
X39930Y-130417D01*
X39487Y-130000D01*
X39043Y-129833D01*
X38473D01*
G01X39043D02*
X39423Y-129583D01*
X39740Y-129167D01*
X39867Y-128667D01*
X39740Y-128167D01*
X39423Y-127750D01*
X38853Y-127500D01*
X38283Y-127583D01*
X37713Y-127917D01*
G01X44017Y-134167D02*
X44650Y-133333D01*
X44967Y-132500D01*
Y-129167D01*
X44650Y-128333D01*
X44017Y-127500D01*
G01X47407Y-131500D02*
X47787Y-132083D01*
X48293Y-132417D01*
X48863Y-132500D01*
X49370Y-132417D01*
X49877Y-132000D01*
X50193Y-131500D01*
X50257Y-131000D01*
X50130Y-130417D01*
X49687Y-130000D01*
X49243Y-129833D01*
X48673D01*
G01X49243D02*
X49623Y-129583D01*
X49940Y-129167D01*
X50067Y-128667D01*
X49940Y-128167D01*
X49623Y-127750D01*
X49053Y-127500D01*
X48483Y-127583D01*
X47913Y-127917D01*
G01X52697Y-128333D02*
X53077Y-127833D01*
X53520Y-127583D01*
X54027Y-127500D01*
X54660Y-127667D01*
X55103Y-128083D01*
X55230Y-128583D01*
X55167Y-129083D01*
X54913Y-129500D01*
X53647Y-130333D01*
X53077Y-130917D01*
X52697Y-131750D01*
X52570Y-132500D01*
X55230D01*
G01X58873D02*
X59000Y-131417D01*
X59190Y-130500D01*
X59443Y-129667D01*
X59760Y-128750D01*
X60267Y-127500D01*
X57733D01*
G01X63277Y-130833D02*
X64923D01*
G01X67997Y-128333D02*
X68377Y-127833D01*
X68820Y-127583D01*
X69327Y-127500D01*
X69960Y-127667D01*
X70403Y-128083D01*
X70530Y-128583D01*
X70467Y-129083D01*
X70213Y-129500D01*
X68947Y-130333D01*
X68377Y-130917D01*
X67997Y-131750D01*
X67870Y-132500D01*
X70530D01*
G01X72907Y-131500D02*
X73287Y-132083D01*
X73793Y-132417D01*
X74363Y-132500D01*
X74870Y-132417D01*
X75377Y-132000D01*
X75693Y-131500D01*
X75757Y-131000D01*
X75630Y-130417D01*
X75187Y-130000D01*
X74743Y-129833D01*
X74173D01*
G01X74743D02*
X75123Y-129583D01*
X75440Y-129167D01*
X75567Y-128667D01*
X75440Y-128167D01*
X75123Y-127750D01*
X74553Y-127500D01*
X73983Y-127583D01*
X73413Y-127917D01*
G01X80160Y-132500D02*
Y-127500D01*
X77817Y-131083D01*
X80983D01*
G01X83107Y-131750D02*
X83487Y-132167D01*
X83930Y-132417D01*
X84500Y-132500D01*
X85070Y-132333D01*
X85513Y-132000D01*
X85830Y-131417D01*
X85893Y-130750D01*
X85767Y-130083D01*
X85450Y-129667D01*
X85007Y-129333D01*
X84563Y-129250D01*
X84120Y-129333D01*
X83550Y-129667D01*
X83740Y-127500D01*
X85450D01*
G01X93497Y-132500D02*
Y-127500D01*
X95903D01*
G01X95017Y-129917D02*
X93497D01*
G01X98217Y-132500D02*
X99800Y-127500D01*
X101383Y-132500D01*
G01X100813Y-130750D02*
X98787D01*
G01X103570Y-132500D02*
X106230Y-127500D01*
G01X103570D02*
X106230Y-132500D01*
G01X110000Y-132667D02*
X109873Y-132583D01*
Y-132417D01*
X110000Y-132333D01*
X110127Y-132417D01*
Y-132583D01*
X110000Y-132667D01*
G01Y-130417D02*
X109873Y-130333D01*
Y-130167D01*
X110000Y-130083D01*
X110127Y-130167D01*
Y-130333D01*
X110000Y-130417D01*
G01X114783Y-134167D02*
X114150Y-133333D01*
X113833Y-132500D01*
Y-129167D01*
X114150Y-128333D01*
X114783Y-127500D01*
G01X120200D02*
X119693Y-127667D01*
X119313Y-128083D01*
X119060Y-128583D01*
X118870Y-129250D01*
X118807Y-130000D01*
X118870Y-130750D01*
X119060Y-131417D01*
X119313Y-131917D01*
X119693Y-132333D01*
X120200Y-132500D01*
X120707Y-132333D01*
X121087Y-131917D01*
X121340Y-131417D01*
X121530Y-130750D01*
X121593Y-130000D01*
X121530Y-129250D01*
X121340Y-128583D01*
X121087Y-128083D01*
X120707Y-127667D01*
X120200Y-127500D01*
G01X123907Y-131500D02*
X124287Y-132083D01*
X124793Y-132417D01*
X125363Y-132500D01*
X125870Y-132417D01*
X126377Y-132000D01*
X126693Y-131500D01*
X126757Y-131000D01*
X126630Y-130417D01*
X126187Y-130000D01*
X125743Y-129833D01*
X125173D01*
G01X125743D02*
X126123Y-129583D01*
X126440Y-129167D01*
X126567Y-128667D01*
X126440Y-128167D01*
X126123Y-127750D01*
X125553Y-127500D01*
X124983Y-127583D01*
X124413Y-127917D01*
G01X130717Y-134167D02*
X131350Y-133333D01*
X131667Y-132500D01*
Y-129167D01*
X131350Y-128333D01*
X130717Y-127500D01*
G01X134107Y-131500D02*
X134487Y-132083D01*
X134993Y-132417D01*
X135563Y-132500D01*
X136070Y-132417D01*
X136577Y-132000D01*
X136893Y-131500D01*
X136957Y-131000D01*
X136830Y-130417D01*
X136387Y-130000D01*
X135943Y-129833D01*
X135373D01*
G01X135943D02*
X136323Y-129583D01*
X136640Y-129167D01*
X136767Y-128667D01*
X136640Y-128167D01*
X136323Y-127750D01*
X135753Y-127500D01*
X135183Y-127583D01*
X134613Y-127917D01*
G01X139523Y-131917D02*
X139967Y-132333D01*
X140473Y-132500D01*
X140980Y-132333D01*
X141423Y-131833D01*
X141740Y-131083D01*
X141867Y-130333D01*
Y-129417D01*
X141740Y-128667D01*
X141423Y-128000D01*
X141043Y-127667D01*
X140600Y-127500D01*
X140093Y-127667D01*
X139713Y-128000D01*
X139460Y-128500D01*
X139333Y-129167D01*
X139460Y-129750D01*
X139777Y-130333D01*
X140157Y-130667D01*
X140600Y-130750D01*
X141107Y-130583D01*
X141487Y-130167D01*
X141867Y-129417D01*
G01X145573Y-132500D02*
X145700Y-131417D01*
X145890Y-130500D01*
X146143Y-129667D01*
X146460Y-128750D01*
X146967Y-127500D01*
X144433D01*
G01X149977Y-130833D02*
X151623D01*
G01X154507Y-131500D02*
X154887Y-132083D01*
X155393Y-132417D01*
X155963Y-132500D01*
X156470Y-132417D01*
X156977Y-132000D01*
X157293Y-131500D01*
X157357Y-131000D01*
X157230Y-130417D01*
X156787Y-130000D01*
X156343Y-129833D01*
X155773D01*
G01X156343D02*
X156723Y-129583D01*
X157040Y-129167D01*
X157167Y-128667D01*
X157040Y-128167D01*
X156723Y-127750D01*
X156153Y-127500D01*
X155583Y-127583D01*
X155013Y-127917D01*
G01X159797Y-130417D02*
X160240Y-129833D01*
X160620Y-129500D01*
X161127Y-129333D01*
X161570Y-129500D01*
X161887Y-129833D01*
X162140Y-130333D01*
X162203Y-130917D01*
X162140Y-131417D01*
X161887Y-131917D01*
X161507Y-132333D01*
X161063Y-132500D01*
X160557Y-132333D01*
X160113Y-131833D01*
X159860Y-131083D01*
X159797Y-130250D01*
X159923Y-129167D01*
X160113Y-128583D01*
X160430Y-128000D01*
X160873Y-127583D01*
X161317Y-127500D01*
X161760Y-127667D01*
X162077Y-128083D01*
G01X166100Y-132500D02*
Y-127500D01*
X165340Y-128500D01*
G01Y-132500D02*
X166860D01*
G01X171960D02*
Y-127500D01*
X169617Y-131083D01*
X172783D01*
G01X191000Y-62500D02*
Y-137500D01*
G01Y-112500D02*
X294000D01*
Y-87500D01*
G01X191000D02*
X294000D01*
G01X301507Y-122500D02*
Y-117500D01*
X302773D01*
X303280Y-117750D01*
X303660Y-118083D01*
X303977Y-118583D01*
X304230Y-119167D01*
X304293Y-120000D01*
X304230Y-120833D01*
X303977Y-121417D01*
X303660Y-121917D01*
X303280Y-122250D01*
X302773Y-122500D01*
X301507D01*
G01X306417D02*
X308000Y-117500D01*
X309583Y-122500D01*
G01X309013Y-120750D02*
X306987D01*
G01X313100Y-117500D02*
Y-122500D01*
G01X311643Y-117500D02*
X314557D01*
G01X319467Y-122500D02*
X316933D01*
Y-117500D01*
X319467D01*
G01X318453Y-119917D02*
X316933D01*
G01X323300Y-122667D02*
X323173Y-122583D01*
Y-122417D01*
X323300Y-122333D01*
X323427Y-122417D01*
Y-122583D01*
X323300Y-122667D01*
G01Y-120417D02*
X323173Y-120333D01*
Y-120167D01*
X323300Y-120083D01*
X323427Y-120167D01*
Y-120333D01*
X323300Y-120417D01*
G01X296000Y-62500D02*
Y-137500D01*
G01X294000Y-62500D02*
Y-137500D01*
G01X301633Y-97500D02*
Y-92500D01*
X303153D01*
X303660Y-92750D01*
X304040Y-93333D01*
X304167Y-94000D01*
X304040Y-94667D01*
X303723Y-95167D01*
X303153Y-95417D01*
X301633D01*
G01X306860Y-97667D02*
X309140Y-92500D01*
G01X311643Y-97500D02*
Y-92500D01*
X314557Y-97500D01*
Y-92500D01*
G01X318200Y-97667D02*
X318073Y-97583D01*
Y-97417D01*
X318200Y-97333D01*
X318327Y-97417D01*
Y-97583D01*
X318200Y-97667D01*
G01Y-95417D02*
X318073Y-95333D01*
Y-95167D01*
X318200Y-95083D01*
X318327Y-95167D01*
Y-95333D01*
X318200Y-95417D01*
G01X296000Y-112500D02*
X496000D01*
G01X301633Y-72500D02*
Y-67500D01*
X303153D01*
X303660Y-67750D01*
X304040Y-68333D01*
X304167Y-69000D01*
X304040Y-69667D01*
X303723Y-70167D01*
X303153Y-70417D01*
X301633D01*
G01X306733Y-72500D02*
Y-67500D01*
X308317D01*
X308823Y-67750D01*
X309140Y-68083D01*
X309267Y-68750D01*
X309140Y-69417D01*
X308760Y-69833D01*
X308317Y-70083D01*
X306733D01*
G01X308317D02*
X309267Y-72500D01*
G01X313100D02*
X312593Y-72417D01*
X312150Y-72083D01*
X311770Y-71583D01*
X311517Y-71000D01*
X311390Y-70333D01*
Y-69667D01*
X311517Y-69000D01*
X311770Y-68417D01*
X312150Y-67917D01*
X312593Y-67583D01*
X313100Y-67500D01*
X313607Y-67583D01*
X314050Y-67917D01*
X314430Y-68417D01*
X314683Y-69000D01*
X314810Y-69667D01*
Y-70333D01*
X314683Y-71000D01*
X314430Y-71583D01*
X314050Y-72083D01*
X313607Y-72417D01*
X313100Y-72500D01*
G01X316933Y-71500D02*
X317250Y-72000D01*
X317630Y-72333D01*
X318073Y-72500D01*
X318580Y-72333D01*
X318960Y-72000D01*
X319340Y-71500D01*
X319467Y-70833D01*
Y-67500D01*
G01X324567Y-72500D02*
X322033D01*
Y-67500D01*
X324567D01*
G01X323553Y-69917D02*
X322033D01*
G01X329793Y-67917D02*
X329413Y-67667D01*
X328970Y-67500D01*
X328463D01*
X327893Y-67750D01*
X327450Y-68167D01*
X327133Y-68667D01*
X326880Y-69500D01*
X326817Y-70250D01*
X326943Y-71000D01*
X327133Y-71500D01*
X327513Y-72000D01*
X327957Y-72333D01*
X328400Y-72500D01*
X328843D01*
X329287Y-72333D01*
X329667Y-72083D01*
X329983Y-71750D01*
G01X333500Y-67500D02*
Y-72500D01*
G01X332043Y-67500D02*
X334957D01*
G01X338600Y-72667D02*
X338473Y-72583D01*
Y-72417D01*
X338600Y-72333D01*
X338727Y-72417D01*
Y-72583D01*
X338600Y-72667D01*
G01Y-70417D02*
X338473Y-70333D01*
Y-70167D01*
X338600Y-70083D01*
X338727Y-70167D01*
Y-70333D01*
X338600Y-70417D01*
G01X296000Y-87500D02*
X496000D01*
G01X411000Y-112500D02*
Y-137500D01*
G01X416633Y-122500D02*
Y-117500D01*
X418217D01*
X418723Y-117750D01*
X419040Y-118083D01*
X419167Y-118750D01*
X419040Y-119417D01*
X418660Y-119833D01*
X418217Y-120083D01*
X416633D01*
G01X418217D02*
X419167Y-122500D01*
G01X424267D02*
X421733D01*
Y-117500D01*
X424267D01*
G01X423253Y-119917D02*
X421733D01*
G01X426517Y-117500D02*
X428100Y-122500D01*
X429683Y-117500D01*
G01X433200Y-122667D02*
X433073Y-122583D01*
Y-122417D01*
X433200Y-122333D01*
X433327Y-122417D01*
Y-122583D01*
X433200Y-122667D01*
G01Y-120417D02*
X433073Y-120333D01*
Y-120167D01*
X433200Y-120083D01*
X433327Y-120167D01*
Y-120333D01*
X433200Y-120417D01*
G01X460000Y-112500D02*
Y-137500D01*
G01X-723776Y2987387D02*
Y-376795D01*
Y-489221D01*
X1782976D01*
Y-376795D01*
Y2987387D01*
X-723776D01*
G01X6705Y-124160D02*
X7332Y-124685D01*
X8037Y-125000D01*
X8663D01*
X9290Y-124685D01*
X9760Y-124160D01*
X9995Y-123425D01*
X9838Y-122690D01*
X9447Y-122060D01*
X8742Y-121640D01*
X7802Y-121430D01*
X7253Y-121010D01*
X7018Y-120275D01*
X7175Y-119540D01*
X7567Y-119015D01*
X8115Y-118700D01*
X8663D01*
X9212Y-118910D01*
X9682Y-119435D01*
G01X13005Y-125000D02*
Y-118700D01*
G01X16295D02*
Y-125000D01*
G01Y-121850D02*
X13005D01*
G01X20010Y-118700D02*
X21890D01*
G01X20950D02*
Y-125000D01*
G01X20010D02*
X21890D01*
G01X28817D02*
X25683D01*
Y-118700D01*
X28817D01*
G01X27563Y-121745D02*
X25683D01*
G01X31748Y-125000D02*
Y-118700D01*
X35352Y-125000D01*
Y-118700D01*
G01X39693Y-126155D02*
X40007Y-124790D01*
G01X46150Y-118700D02*
Y-125000D01*
G01X44348Y-118700D02*
X47952D01*
G01X50492Y-125000D02*
X52450Y-118700D01*
X54408Y-125000D01*
G01X53703Y-122795D02*
X51197D01*
G01X57810Y-118700D02*
X59690D01*
G01X58750D02*
Y-125000D01*
G01X57810D02*
X59690D01*
G01X62700Y-118700D02*
X63797Y-125000D01*
X65050Y-118700D01*
X66303Y-125000D01*
X67400Y-118700D01*
G01X69392Y-125000D02*
X71350Y-118700D01*
X73308Y-125000D01*
G01X72603Y-122795D02*
X70097D01*
G01X75848Y-125000D02*
Y-118700D01*
X79452Y-125000D01*
Y-118700D01*
G01X88683Y-125000D02*
Y-118700D01*
X90642D01*
X91268Y-119015D01*
X91660Y-119435D01*
X91817Y-120275D01*
X91660Y-121115D01*
X91190Y-121640D01*
X90642Y-121955D01*
X88683D01*
G01X90642D02*
X91817Y-125000D01*
G01X96550Y-125210D02*
X96393Y-125105D01*
Y-124895D01*
X96550Y-124790D01*
X96707Y-124895D01*
Y-125105D01*
X96550Y-125210D01*
G01X102850Y-125000D02*
X102223Y-124895D01*
X101675Y-124475D01*
X101205Y-123845D01*
X100892Y-123110D01*
X100735Y-122270D01*
Y-121430D01*
X100892Y-120590D01*
X101205Y-119855D01*
X101675Y-119225D01*
X102223Y-118805D01*
X102850Y-118700D01*
X103477Y-118805D01*
X104025Y-119225D01*
X104495Y-119855D01*
X104808Y-120590D01*
X104965Y-121430D01*
Y-122270D01*
X104808Y-123110D01*
X104495Y-123845D01*
X104025Y-124475D01*
X103477Y-124895D01*
X102850Y-125000D01*
G01X109150Y-125210D02*
X108993Y-125105D01*
Y-124895D01*
X109150Y-124790D01*
X109307Y-124895D01*
Y-125105D01*
X109150Y-125210D01*
G01X117173Y-119225D02*
X116703Y-118910D01*
X116155Y-118700D01*
X115528D01*
X114823Y-119015D01*
X114275Y-119540D01*
X113883Y-120170D01*
X113570Y-121220D01*
X113492Y-122165D01*
X113648Y-123110D01*
X113883Y-123740D01*
X114353Y-124370D01*
X114902Y-124790D01*
X115450Y-125000D01*
X115998D01*
X116547Y-124790D01*
X117017Y-124475D01*
X117408Y-124055D01*
G01X121750Y-125210D02*
X121593Y-125105D01*
Y-124895D01*
X121750Y-124790D01*
X121907Y-124895D01*
Y-125105D01*
X121750Y-125210D01*
G01X6627Y-115000D02*
Y-108700D01*
G01X9603D02*
X6627Y-112585D01*
G01X10073Y-115000D02*
X7958Y-110800D01*
G01X12927Y-108700D02*
Y-113215D01*
X13240Y-114160D01*
X13867Y-114790D01*
X14650Y-115000D01*
X15433Y-114790D01*
X16060Y-114160D01*
X16373Y-113215D01*
Y-108700D01*
G01X22517Y-115000D02*
X19383D01*
Y-108700D01*
X22517D01*
G01X21263Y-111745D02*
X19383D01*
G01X26310Y-108700D02*
X28190D01*
G01X27250D02*
Y-115000D01*
G01X26310D02*
X28190D01*
G01X38205Y-114160D02*
X38832Y-114685D01*
X39537Y-115000D01*
X40163D01*
X40790Y-114685D01*
X41260Y-114160D01*
X41495Y-113425D01*
X41338Y-112690D01*
X40947Y-112060D01*
X40242Y-111640D01*
X39302Y-111430D01*
X38753Y-111010D01*
X38518Y-110275D01*
X38675Y-109540D01*
X39067Y-109015D01*
X39615Y-108700D01*
X40163D01*
X40712Y-108910D01*
X41182Y-109435D01*
G01X44505Y-115000D02*
Y-108700D01*
G01X47795D02*
Y-115000D01*
G01Y-111850D02*
X44505D01*
G01X50492Y-115000D02*
X52450Y-108700D01*
X54408Y-115000D01*
G01X53703Y-112795D02*
X51197D01*
G01X56948Y-115000D02*
Y-108700D01*
X60552Y-115000D01*
Y-108700D01*
G01X69705Y-115000D02*
Y-108700D01*
G01X72995D02*
Y-115000D01*
G01Y-111850D02*
X69705D01*
G01X76005Y-114160D02*
X76632Y-114685D01*
X77337Y-115000D01*
X77963D01*
X78590Y-114685D01*
X79060Y-114160D01*
X79295Y-113425D01*
X79138Y-112690D01*
X78747Y-112060D01*
X78042Y-111640D01*
X77102Y-111430D01*
X76553Y-111010D01*
X76318Y-110275D01*
X76475Y-109540D01*
X76867Y-109015D01*
X77415Y-108700D01*
X77963D01*
X78512Y-108910D01*
X78982Y-109435D01*
G01X83010Y-108700D02*
X84890D01*
G01X83950D02*
Y-115000D01*
G01X83010D02*
X84890D01*
G01X88292D02*
X90250Y-108700D01*
X92208Y-115000D01*
G01X91503Y-112795D02*
X88997D01*
G01X94748Y-115000D02*
Y-108700D01*
X98352Y-115000D01*
Y-108700D01*
G01X103320Y-111850D02*
X104887D01*
Y-113740D01*
X104417Y-114370D01*
X103868Y-114790D01*
X103085Y-115000D01*
X102302Y-114790D01*
X101753Y-114370D01*
X101283Y-113740D01*
X100970Y-113005D01*
X100813Y-112165D01*
Y-111430D01*
X100970Y-110800D01*
X101283Y-110065D01*
X101753Y-109435D01*
X102223Y-109015D01*
X102850Y-108700D01*
X103398D01*
X104025Y-108910D01*
X104495Y-109330D01*
G01X108993Y-116155D02*
X109307Y-114790D01*
G01X115450Y-108700D02*
Y-115000D01*
G01X113648Y-108700D02*
X117252D01*
G01X119792Y-115000D02*
X121750Y-108700D01*
X123708Y-115000D01*
G01X123003Y-112795D02*
X120497D01*
G01X128050Y-115000D02*
X127423Y-114895D01*
X126875Y-114475D01*
X126405Y-113845D01*
X126092Y-113110D01*
X125935Y-112270D01*
Y-111430D01*
X126092Y-110590D01*
X126405Y-109855D01*
X126875Y-109225D01*
X127423Y-108805D01*
X128050Y-108700D01*
X128677Y-108805D01*
X129225Y-109225D01*
X129695Y-109855D01*
X130008Y-110590D01*
X130165Y-111430D01*
Y-112270D01*
X130008Y-113110D01*
X129695Y-113845D01*
X129225Y-114475D01*
X128677Y-114895D01*
X128050Y-115000D01*
G01X140650D02*
Y-112165D01*
X139083Y-108700D01*
G01X142217D02*
X140650Y-112165D01*
G01X145227Y-108700D02*
Y-113215D01*
X145540Y-114160D01*
X146167Y-114790D01*
X146950Y-115000D01*
X147733Y-114790D01*
X148360Y-114160D01*
X148673Y-113215D01*
Y-108700D01*
G01X151292Y-115000D02*
X153250Y-108700D01*
X155208Y-115000D01*
G01X154503Y-112795D02*
X151997D01*
G01X157748Y-115000D02*
Y-108700D01*
X161352Y-115000D01*
Y-108700D01*
G01X30650Y-92300D02*
X28130Y-91883D01*
X25925Y-90217D01*
X24035Y-87717D01*
X22775Y-84800D01*
X22145Y-81467D01*
Y-78133D01*
X22775Y-74800D01*
X24035Y-71883D01*
X25925Y-69384D01*
X28130Y-67717D01*
X30650Y-67300D01*
X33170Y-67717D01*
X35375Y-69384D01*
X37265Y-71883D01*
X38525Y-74800D01*
X39155Y-78133D01*
Y-81467D01*
X38525Y-84800D01*
X37265Y-87717D01*
X35375Y-90217D01*
X33170Y-91883D01*
X30650Y-92300D01*
G01X33170Y-85633D02*
X36950Y-92300D01*
G01X50495Y-75634D02*
Y-87300D01*
X51755Y-90217D01*
X53645Y-91883D01*
X55850Y-92300D01*
X58055Y-91883D01*
X59945Y-90217D01*
X61205Y-87300D01*
G01Y-92300D02*
Y-75634D01*
G01X86720Y-92300D02*
Y-75634D01*
G01Y-78550D02*
X85460Y-76884D01*
X83570Y-76050D01*
X81365Y-75634D01*
X79160Y-76467D01*
X77270Y-78133D01*
X76010Y-80634D01*
X75380Y-83967D01*
X76010Y-87300D01*
X77270Y-89801D01*
X79160Y-91467D01*
X81365Y-92300D01*
X83570Y-91883D01*
X85460Y-90634D01*
X86720Y-88967D01*
G01X100895Y-92300D02*
Y-75634D01*
G01Y-79800D02*
X102155Y-77717D01*
X104045Y-76050D01*
X106565Y-75634D01*
X108770Y-76050D01*
X110660Y-77717D01*
X111605Y-80634D01*
Y-92300D01*
G01X131450Y-67300D02*
Y-92300D01*
G01X127040Y-75634D02*
X135860D01*
G01X162320Y-92300D02*
Y-75634D01*
G01Y-78550D02*
X161060Y-76884D01*
X159170Y-76050D01*
X156965Y-75634D01*
X154760Y-76467D01*
X152870Y-78133D01*
X151610Y-80634D01*
X150980Y-83967D01*
X151610Y-87300D01*
X152870Y-89801D01*
X154760Y-91467D01*
X156965Y-92300D01*
X159170Y-91883D01*
X161060Y-90634D01*
X162320Y-88967D01*
G01X6548Y-105000D02*
Y-98700D01*
X10152Y-105000D01*
Y-98700D01*
G01X14650Y-105000D02*
X14023Y-104895D01*
X13475Y-104475D01*
X13005Y-103845D01*
X12692Y-103110D01*
X12535Y-102270D01*
Y-101430D01*
X12692Y-100590D01*
X13005Y-99855D01*
X13475Y-99225D01*
X14023Y-98805D01*
X14650Y-98700D01*
X15277Y-98805D01*
X15825Y-99225D01*
X16295Y-99855D01*
X16608Y-100590D01*
X16765Y-101430D01*
Y-102270D01*
X16608Y-103110D01*
X16295Y-103845D01*
X15825Y-104475D01*
X15277Y-104895D01*
X14650Y-105000D01*
G01X20950Y-105210D02*
X20793Y-105105D01*
Y-104895D01*
X20950Y-104790D01*
X21107Y-104895D01*
Y-105105D01*
X20950Y-105210D01*
G01X27250Y-105000D02*
Y-98700D01*
X26310Y-99960D01*
G01Y-105000D02*
X28190D01*
G01X33550D02*
X34098Y-104895D01*
X34725Y-104580D01*
X35117Y-104055D01*
X35273Y-103320D01*
X35117Y-102585D01*
X34647Y-101955D01*
X33942Y-101640D01*
X33158D01*
X32688Y-101430D01*
X32297Y-100905D01*
X32140Y-100170D01*
X32375Y-99435D01*
X32923Y-98910D01*
X33550Y-98700D01*
X34177Y-98910D01*
X34725Y-99435D01*
X34960Y-100170D01*
X34803Y-100905D01*
X34412Y-101430D01*
X33942Y-101640D01*
X33158D01*
X32453Y-101955D01*
X31983Y-102585D01*
X31827Y-103320D01*
X31983Y-104055D01*
X32375Y-104580D01*
X33002Y-104895D01*
X33550Y-105000D01*
G01X39850D02*
X40398Y-104895D01*
X41025Y-104580D01*
X41417Y-104055D01*
X41573Y-103320D01*
X41417Y-102585D01*
X40947Y-101955D01*
X40242Y-101640D01*
X39458D01*
X38988Y-101430D01*
X38597Y-100905D01*
X38440Y-100170D01*
X38675Y-99435D01*
X39223Y-98910D01*
X39850Y-98700D01*
X40477Y-98910D01*
X41025Y-99435D01*
X41260Y-100170D01*
X41103Y-100905D01*
X40712Y-101430D01*
X40242Y-101640D01*
X39458D01*
X38753Y-101955D01*
X38283Y-102585D01*
X38127Y-103320D01*
X38283Y-104055D01*
X38675Y-104580D01*
X39302Y-104895D01*
X39850Y-105000D01*
G01X45993Y-106155D02*
X46307Y-104790D01*
G01X50100Y-98700D02*
X51197Y-105000D01*
X52450Y-98700D01*
X53703Y-105000D01*
X54800Y-98700D01*
G01X60317Y-105000D02*
X57183D01*
Y-98700D01*
X60317D01*
G01X59063Y-101745D02*
X57183D01*
G01X63248Y-105000D02*
Y-98700D01*
X66852Y-105000D01*
Y-98700D01*
G01X76005Y-105000D02*
Y-98700D01*
G01X79295D02*
Y-105000D01*
G01Y-101850D02*
X76005D01*
G01X81600Y-98700D02*
X82697Y-105000D01*
X83950Y-98700D01*
X85203Y-105000D01*
X86300Y-98700D01*
G01X88292Y-105000D02*
X90250Y-98700D01*
X92208Y-105000D01*
G01X91503Y-102795D02*
X88997D01*
G01X101362Y-99750D02*
X101832Y-99120D01*
X102380Y-98805D01*
X103007Y-98700D01*
X103790Y-98910D01*
X104338Y-99435D01*
X104495Y-100065D01*
X104417Y-100695D01*
X104103Y-101220D01*
X102537Y-102270D01*
X101832Y-103005D01*
X101362Y-104055D01*
X101205Y-105000D01*
X104495D01*
G01X107348D02*
Y-98700D01*
X110952Y-105000D01*
Y-98700D01*
G01X113727Y-105000D02*
Y-98700D01*
X115293D01*
X115920Y-99015D01*
X116390Y-99435D01*
X116782Y-100065D01*
X117095Y-100800D01*
X117173Y-101850D01*
X117095Y-102900D01*
X116782Y-103635D01*
X116390Y-104265D01*
X115920Y-104685D01*
X115293Y-105000D01*
X113727D01*
G01X126483D02*
Y-98700D01*
X128442D01*
X129068Y-99015D01*
X129460Y-99435D01*
X129617Y-100275D01*
X129460Y-101115D01*
X128990Y-101640D01*
X128442Y-101955D01*
X126483D01*
G01X128442D02*
X129617Y-105000D01*
G01X132627D02*
Y-98700D01*
X134193D01*
X134820Y-99015D01*
X135290Y-99435D01*
X135682Y-100065D01*
X135995Y-100800D01*
X136073Y-101850D01*
X135995Y-102900D01*
X135682Y-103635D01*
X135290Y-104265D01*
X134820Y-104685D01*
X134193Y-105000D01*
X132627D01*
G01X140650Y-105210D02*
X140493Y-105105D01*
Y-104895D01*
X140650Y-104790D01*
X140807Y-104895D01*
Y-105105D01*
X140650Y-105210D01*
G01X11677Y572812D02*
Y559897D01*
X11692Y559882D01*
G01X9606Y599901D02*
X5525Y603982D01*
Y634059D01*
X10477Y639011D01*
Y716371D01*
X7673Y719175D01*
G01X9606Y627264D02*
Y633703D01*
X12289Y636386D01*
Y708713D01*
X15597Y712021D01*
X28129D01*
X31717Y708433D01*
X68203D01*
X85707Y725937D01*
Y780614D01*
X104187Y799094D01*
Y929211D01*
X98323Y935075D01*
Y975987D01*
X106310Y983974D01*
Y1031601D01*
X128654Y1053945D01*
Y1103099D01*
X123616Y1108137D01*
X111394D01*
X101467Y1118064D01*
Y1129442D01*
X109932Y1137907D01*
Y1217099D01*
X103359Y1223672D01*
Y1337589D01*
X99917Y1341031D01*
X94790D01*
X82790Y1353031D01*
X39628D01*
X35691Y1356968D01*
X25393D01*
G01X15547Y707364D02*
X18475Y710292D01*
X26769D01*
X30037Y707024D01*
X69035D01*
X87319Y725308D01*
Y779400D01*
X106185Y798266D01*
Y930717D01*
X100215Y936687D01*
Y975531D01*
X107946Y983262D01*
Y1030411D01*
X130195Y1052660D01*
Y1109649D01*
X123216Y1116628D01*
X117807D01*
X115039Y1113860D01*
X109673D01*
X105152Y1118381D01*
G01X70865Y872278D02*
X68650Y870063D01*
X58106D01*
X38096Y850053D01*
X30570D01*
X26456Y845939D01*
X24363D01*
X19497Y841073D01*
Y837299D01*
X15547Y833349D01*
G01X70865Y890116D02*
X56817D01*
X46176Y879475D01*
Y876845D01*
X34377Y865046D01*
X30921D01*
X27163Y861288D01*
X24608D01*
X17055Y853735D01*
X15026D01*
X10780Y849489D01*
Y840393D01*
X7673Y837286D01*
G01X15547Y841223D02*
X19880Y845556D01*
Y849922D01*
X23449Y853491D01*
X27358D01*
X29935Y856068D01*
X41243D01*
X56891Y871716D01*
X63542D01*
X70441Y878615D01*
X90708D01*
G01X70865Y866278D02*
X70765Y866378D01*
X59406D01*
X35247Y842219D01*
X33726D01*
X30288Y838781D01*
Y831961D01*
X27739Y829412D01*
X7673D01*
G01X92216Y899865D02*
X95482Y903131D01*
Y907850D01*
X93026Y910306D01*
X56811D01*
X35251Y888746D01*
X31698D01*
X28590Y885638D01*
X25660D01*
X19948Y879926D01*
Y872485D01*
X16116Y868653D01*
X14087D01*
X10630Y865196D01*
Y863865D01*
X7673Y860908D01*
G01X15547Y856971D02*
X19874Y861298D01*
Y864596D01*
X24683Y869405D01*
X27088D01*
X30395Y872712D01*
X35580D01*
X38829Y875961D01*
Y885116D01*
X61117Y907404D01*
X92633D01*
G01X15547Y990829D02*
X18741Y994023D01*
X28280D01*
X30589Y991714D01*
X97384D01*
X98139Y990959D01*
G01X7673Y994766D02*
X12970D01*
X13922Y995718D01*
X28602D01*
X31754Y998870D01*
X38667D01*
X41298Y1001501D01*
X98577D01*
X100687Y999391D01*
G01X15551Y1278228D02*
X18682Y1281359D01*
X28221D01*
X30399Y1279181D01*
X40717D01*
X41319Y1279783D01*
X51432D01*
G01X51398Y1267290D02*
X42592D01*
X38443Y1271439D01*
X31454D01*
X28602Y1274291D01*
X7677D01*
G01X51060Y1263103D02*
X43096D01*
X36826Y1269373D01*
X29987D01*
X27808Y1267194D01*
X18711D01*
X15551Y1270354D01*
G01X9606Y1471949D02*
X17480Y1464075D01*
Y1391881D01*
X19382Y1389979D01*
Y1361143D01*
X20885Y1359640D01*
Y1357232D01*
X25086Y1353031D01*
X33267D01*
G01X9606Y1499311D02*
X5511Y1495216D01*
Y1468362D01*
X13897Y1459976D01*
Y1392455D01*
X12355Y1390913D01*
Y1362831D01*
X14431Y1360755D01*
X16760D01*
X18827Y1358688D01*
Y1355660D01*
X25393Y1349094D01*
G01X16484Y1558309D02*
Y1566800D01*
X21495Y1571811D01*
G01X11085Y1558441D02*
Y1564701D01*
X11692Y1565308D01*
Y1571811D01*
G01X70865Y860278D02*
X56255D01*
X33263Y837286D01*
G01X100719Y1318810D02*
X96536Y1314627D01*
Y1220443D01*
X105386Y1211593D01*
Y1142855D01*
X96798Y1134267D01*
Y1106868D01*
X104438Y1099228D01*
X114383D01*
X116554Y1097057D01*
X122998D01*
X125729Y1094326D01*
Y1057086D01*
X102668Y1034025D01*
Y986181D01*
X93000Y976513D01*
Y932553D01*
X99862Y925691D01*
Y882547D01*
X92382Y875067D01*
X78767D01*
X72260Y868560D01*
X59334D01*
X39138Y848364D01*
X32224D01*
X28259Y844399D01*
Y836219D01*
X25389Y833349D01*
G01X48433Y866179D02*
X39791Y857537D01*
X25955D01*
X25389Y856971D01*
G01X33263Y860908D02*
X40097D01*
X48467Y869278D01*
G01X119920Y1062165D02*
X110384Y1052629D01*
X50204D01*
X33267Y1069566D01*
G01X25393Y1254606D02*
X39344D01*
X46491Y1247459D01*
X78570D01*
X90477Y1259366D01*
Y1320731D01*
X91077Y1321331D01*
X91240D01*
X100719Y1330810D01*
G01X33267Y1258543D02*
X38442D01*
X47096Y1249889D01*
X77220D01*
X87665Y1260334D01*
Y1323756D01*
X100719Y1336810D01*
G01X33267Y1266417D02*
X37302D01*
X46086Y1257633D01*
X51127D01*
G01X51331Y1271544D02*
X43335D01*
X40588Y1274291D01*
X33267D01*
G01X25393Y1278228D02*
X28580D01*
X29130Y1277678D01*
X40908D01*
X42956Y1275630D01*
X51432D01*
G01X51296Y1284038D02*
X35140D01*
X33267Y1282165D01*
G01X46980Y1345843D02*
X64859D01*
X66866Y1343836D01*
Y1336103D01*
G01X46980Y1340843D02*
X45180Y1342643D01*
Y1346615D01*
X46208Y1347643D01*
X66613D01*
X71866Y1342390D01*
Y1336103D01*
G01X25393Y1388464D02*
X35208D01*
X38710Y1384962D01*
Y1361115D01*
X43571Y1356254D01*
X83013D01*
X95458Y1343809D01*
X99119D01*
X105726Y1337202D01*
Y1224830D01*
X111486Y1219070D01*
Y1136973D01*
X102924Y1128411D01*
Y1120609D01*
X105152Y1118381D01*
G01X63820Y573932D02*
X61298Y571410D01*
Y559882D01*
G01X58750Y573866D02*
X51495Y566611D01*
Y559882D01*
G01X100719Y1306810D02*
Y1221942D01*
X108186Y1214475D01*
Y1139261D01*
X99954Y1131029D01*
Y1117568D01*
X111092Y1106430D01*
X122802D01*
X127253Y1101979D01*
Y1055566D01*
X104349Y1032662D01*
Y984285D01*
X96082Y976018D01*
Y934234D01*
X102076Y928240D01*
Y873192D01*
X83162Y854278D01*
X70865D01*
G01X51263Y1253378D02*
Y1257497D01*
X51127Y1257633D01*
G01X61866Y1315303D02*
Y1309190D01*
G01X63061Y1302746D02*
X58752D01*
G01X61866Y1309190D02*
X63061Y1307995D01*
Y1302746D01*
G01X71909Y1302580D02*
X67569D01*
X67568Y1302581D01*
G01D02*
Y1307829D01*
G01D02*
X66866Y1308531D01*
Y1315303D01*
G01X54543Y1302681D02*
X50332D01*
X50331Y1302680D01*
G01X54543Y1302681D02*
Y1308995D01*
G01D02*
X56866Y1311318D01*
Y1315303D01*
G01X61866Y1336103D02*
Y1342104D01*
G01D02*
X55831D01*
X52958Y1339231D01*
G01X61280Y1559138D02*
Y1571793D01*
X61298Y1571811D01*
G01X119920Y416102D02*
X94857D01*
X93223Y417736D01*
G01X139920Y754134D02*
X129251D01*
X124808Y758577D01*
X102883D01*
X95775Y751469D01*
G01X119920Y1062165D02*
X117944Y1064141D01*
X93722D01*
X90920Y1066943D01*
Y1131623D01*
X103051Y1143754D01*
Y1210919D01*
X93179Y1220791D01*
Y1317270D01*
X100719Y1324810D01*
G01Y1346065D02*
Y1385318D01*
X90055Y1395982D01*
Y1448140D01*
X95236Y1453321D01*
G01D02*
X95426Y1453131D01*
X100019D01*
G01X103928Y28320D02*
Y32853D01*
G01X108995Y20080D02*
Y24248D01*
X106958Y26285D01*
G01X103843Y24203D02*
X104876D01*
X106958Y26285D01*
G01X119920Y28071D02*
X108744D01*
X106958Y26285D01*
G01X108995Y15847D02*
Y20080D01*
G01X104932Y41803D02*
X101430D01*
G01X107405Y49898D02*
X107570Y49733D01*
X113546D01*
X115208Y48071D01*
X119920D01*
G01X108090Y46285D02*
Y47822D01*
X107405Y48507D01*
Y49898D01*
G01X103928Y32853D02*
X105203D01*
X107037Y34687D01*
G01X103928Y37438D02*
Y32853D01*
G01X119920Y38071D02*
X110421D01*
X107037Y34687D01*
G01X107263Y75055D02*
Y72244D01*
G01X119920Y58071D02*
X111950D01*
X111771Y58250D01*
X109054D01*
G01D02*
X105877D01*
G01X106836Y376461D02*
X107195Y376102D01*
X119920D01*
G01X103668Y376580D02*
Y371909D01*
G01Y381386D02*
Y376580D01*
G01X106836Y376461D02*
X106717Y376580D01*
X103668D01*
G01Y391220D02*
Y386235D01*
G01Y396024D02*
Y391220D01*
G01X106709Y391219D02*
X114803D01*
X119920Y386102D01*
G01X103668Y391220D02*
X106708D01*
X106709Y391219D01*
G01X100794Y400352D02*
Y402138D01*
X105451Y406795D01*
G01X119920Y396102D02*
X114603D01*
X114498Y396207D01*
G01X103944Y400352D02*
X114108D01*
X119858Y406102D01*
X119920D01*
G01X104206Y720745D02*
Y715937D01*
G01Y725457D02*
Y720745D01*
G01X119920Y724134D02*
X114536D01*
X113302Y725368D01*
X107025D01*
G01X104206Y725457D02*
X106936D01*
X107025Y725368D01*
G01X104206Y730398D02*
Y735248D01*
G01X101520Y749481D02*
Y750559D01*
X105087Y754126D01*
G01X119920Y744134D02*
X114834D01*
X113829Y745139D01*
X106935D01*
G01D02*
X104346D01*
G01X104206Y735248D02*
Y739962D01*
G01X119920Y734134D02*
X114441D01*
X113356Y735219D01*
X107173D01*
G01X104206Y735248D02*
X107144D01*
X107173Y735219D01*
G01X119920Y754134D02*
X119858D01*
X119850Y754126D01*
X109315D01*
X104670Y749481D01*
G01X104339Y1072226D02*
Y1067515D01*
G01X104432Y1096403D02*
X107351Y1093484D01*
G01D02*
X108670Y1092165D01*
X119920D01*
G01X104339Y1087095D02*
Y1081791D01*
G01Y1092036D02*
Y1087095D01*
G01Y1081791D02*
X107235Y1081773D01*
Y1081791D01*
G01D02*
X107261Y1081765D01*
X115317D01*
X115717Y1082165D01*
X119920D01*
G01X104339Y1076901D02*
Y1072226D01*
G01X107215Y1072208D02*
X107552D01*
G01D02*
X107595Y1072165D01*
X119920D01*
G01X107552Y1072208D02*
X104339Y1072226D01*
G01X108779Y1105760D02*
X98459Y1116080D01*
Y1132266D01*
X106786Y1140593D01*
Y1213895D01*
X98241Y1222440D01*
Y1310332D01*
X100719Y1312810D01*
G01X105880Y1102535D02*
Y1102861D01*
X108779Y1105760D01*
G01X109030Y1102535D02*
X114534D01*
X114904Y1102165D01*
X119920D01*
G01Y1430197D02*
X116076Y1434041D01*
X106962D01*
G01X103377Y1419492D02*
X106921D01*
G01X103377Y1424340D02*
Y1419492D01*
G01Y1429195D02*
Y1424340D01*
G01X106921Y1419492D02*
X118288D01*
X118993Y1420197D01*
X119920D01*
G01Y1440197D02*
X111165D01*
X106763Y1444599D01*
G01D02*
X103443Y1447919D01*
G01X103377Y1438980D02*
Y1434041D01*
G01Y1443743D02*
Y1438980D01*
G01X106962Y1434041D02*
X103377D01*
G01X107006Y1452651D02*
X109466Y1450191D01*
X119852D01*
X119858Y1450197D01*
X119920D01*
G01X103169Y1453131D02*
X106526D01*
X107006Y1452651D01*
G01X104827Y1765722D02*
Y1760827D01*
G01Y1770527D02*
Y1765722D01*
G01X107355Y1770437D02*
X117711D01*
X119920Y1768228D01*
G01X104827Y1770527D02*
X107265D01*
X107355Y1770437D01*
G01X107391Y1794460D02*
X105383D01*
X103671Y1796172D01*
Y1798224D01*
G01X119920Y1788228D02*
X110581D01*
X107220Y1791589D01*
G01D02*
X106572D01*
X104930Y1789947D01*
G01X104827Y1780542D02*
X107371D01*
X107373Y1780544D01*
G01X104827Y1785571D02*
Y1780542D01*
G01Y1775514D02*
Y1780542D01*
G01X107373Y1780544D02*
X112823D01*
X115139Y1778228D01*
X119920D01*
G01Y1798228D02*
X115920D01*
X115916Y1798224D01*
X110825D01*
X106819Y1802230D01*
G01D02*
X106821Y1802232D01*
Y1798224D01*
G01X139920Y48071D02*
X139921Y48070D01*
X154202D01*
X157558Y51426D01*
G01X139920Y68071D02*
X143858D01*
X147858Y68070D01*
X147918Y68130D01*
X155313D01*
G01X139920Y396102D02*
X151760D01*
X156865Y401207D01*
G01X156321Y415048D02*
X148721D01*
X147667Y416102D01*
X139920D01*
G01Y744134D02*
X151741D01*
X156610Y749003D01*
Y751063D01*
G01X139920Y764134D02*
X143858D01*
X147858Y764133D01*
X147956Y764231D01*
X155515D01*
G01X139920Y1092165D02*
X147988D01*
X156854Y1101031D01*
G01X139920Y1112165D02*
X145661D01*
X147858Y1112164D01*
X148671Y1112977D01*
X156117D01*
G01X139920Y1440197D02*
X148284D01*
X159192Y1451105D01*
G01X139920Y1460197D02*
X153901D01*
X156355Y1462651D01*
G01X139920Y1480197D02*
X147858D01*
X148758Y1481097D01*
X152213D01*
X153036Y1480274D01*
X155816D01*
G01X156452Y1800821D02*
Y1798275D01*
X146405Y1788228D01*
X139920D01*
G01Y1808228D02*
X144389D01*
X147858Y1808227D01*
X149809D01*
X155413Y1813831D01*
Y1815631D01*
G01X156526Y56744D02*
Y54258D01*
X157558Y53226D01*
Y51426D01*
G01X156865Y401207D02*
Y403217D01*
X155340Y404742D01*
Y407575D01*
G01X161256Y415045D02*
X156324D01*
X156321Y415048D01*
G01X155800Y756757D02*
Y753673D01*
X156610Y752863D01*
Y751063D01*
G01X156854Y1101031D02*
Y1102831D01*
X156128Y1103557D01*
Y1106853D01*
G01X156117Y1112977D02*
X159062D01*
X159070Y1112985D01*
X160870D01*
G01X157102Y1457084D02*
Y1453195D01*
X159192Y1451105D01*
G01X155690Y1807740D02*
Y1805940D01*
X156452Y1805178D01*
Y1800821D01*
G01X158559Y1820360D02*
Y1818877D01*
X155413Y1815731D01*
Y1815631D01*
G01X202000Y-72000D02*
Y-80000D01*
X206000D01*
G01X213800D02*
Y-74667D01*
G01Y-75600D02*
X213400Y-75067D01*
X212800Y-74800D01*
X212100Y-74667D01*
X211400Y-74933D01*
X210800Y-75467D01*
X210400Y-76267D01*
X210200Y-77333D01*
X210400Y-78400D01*
X210800Y-79200D01*
X211400Y-79733D01*
X212100Y-80000D01*
X212800Y-79867D01*
X213400Y-79467D01*
X213800Y-78934D01*
G01X217900Y-82400D02*
X218500Y-82667D01*
X219300Y-82400D01*
X219800Y-81867D01*
X220200Y-81200D01*
X220800Y-79067D01*
X222100Y-74667D01*
G01X218900D02*
X220800Y-79067D01*
G01X226500Y-76400D02*
X229700D01*
X229400Y-75467D01*
X228900Y-74933D01*
X228200Y-74667D01*
X227500Y-74800D01*
X226900Y-75200D01*
X226500Y-76133D01*
X226300Y-76934D01*
Y-77733D01*
X226500Y-78533D01*
X227000Y-79333D01*
X227600Y-79867D01*
X228300Y-80000D01*
X229000Y-79733D01*
X229700Y-78934D01*
G01X234600Y-80000D02*
Y-74667D01*
G01Y-75733D02*
X235100Y-75200D01*
X235600Y-74800D01*
X236300Y-74667D01*
X236800Y-74800D01*
X237400Y-75200D01*
G01X223400Y-128934D02*
X224200Y-129600D01*
X225100Y-130000D01*
X225900D01*
X226700Y-129600D01*
X227300Y-128934D01*
X227600Y-128000D01*
X227400Y-127067D01*
X226900Y-126267D01*
X226000Y-125733D01*
X224800Y-125467D01*
X224100Y-124933D01*
X223800Y-124000D01*
X224000Y-123067D01*
X224500Y-122400D01*
X225200Y-122000D01*
X225900D01*
X226600Y-122267D01*
X227200Y-122933D01*
G01X235300Y-130000D02*
Y-124667D01*
G01Y-125600D02*
X234900Y-125067D01*
X234300Y-124800D01*
X233600Y-124667D01*
X232900Y-124933D01*
X232300Y-125467D01*
X231900Y-126267D01*
X231700Y-127333D01*
X231900Y-128400D01*
X232300Y-129200D01*
X232900Y-129733D01*
X233600Y-130000D01*
X234300Y-129867D01*
X234900Y-129467D01*
X235300Y-128934D01*
G01X239800Y-130000D02*
Y-124667D01*
G01Y-126000D02*
X240200Y-125333D01*
X240800Y-124800D01*
X241600Y-124667D01*
X242300Y-124800D01*
X242900Y-125333D01*
X243200Y-126267D01*
Y-130000D01*
G01X251300Y-122000D02*
Y-130000D01*
G01Y-128800D02*
X250900Y-129467D01*
X250300Y-129867D01*
X249600Y-130000D01*
X248800Y-129733D01*
X248200Y-129067D01*
X247800Y-128267D01*
X247700Y-127333D01*
X247800Y-126400D01*
X248200Y-125600D01*
X248800Y-124933D01*
X249600Y-124667D01*
X250300Y-124800D01*
X250800Y-125067D01*
X251300Y-125600D01*
G01X255400Y-132400D02*
X256000Y-132667D01*
X256800Y-132400D01*
X257300Y-131867D01*
X257700Y-131200D01*
X258300Y-129067D01*
X259600Y-124667D01*
G01X256400D02*
X258300Y-129067D01*
G01X235500Y-97000D02*
Y-105000D01*
G01X233200Y-97000D02*
X237800D01*
G01X243500Y-105000D02*
X242700Y-104867D01*
X242000Y-104333D01*
X241400Y-103533D01*
X241000Y-102600D01*
X240800Y-101533D01*
Y-100467D01*
X241000Y-99400D01*
X241400Y-98467D01*
X242000Y-97667D01*
X242700Y-97133D01*
X243500Y-97000D01*
X244300Y-97133D01*
X245000Y-97667D01*
X245600Y-98467D01*
X246000Y-99400D01*
X246200Y-100467D01*
Y-101533D01*
X246000Y-102600D01*
X245600Y-103533D01*
X245000Y-104333D01*
X244300Y-104867D01*
X243500Y-105000D01*
G01X249500D02*
Y-97000D01*
X251900D01*
X252700Y-97400D01*
X253300Y-98333D01*
X253500Y-99400D01*
X253300Y-100467D01*
X252800Y-101267D01*
X251900Y-101667D01*
X249500D01*
G01X255500Y-80000D02*
Y-72000D01*
X254300Y-73600D01*
G01Y-80000D02*
X256700D01*
G01X328600Y-123333D02*
X329200Y-122533D01*
X329900Y-122133D01*
X330700Y-122000D01*
X331700Y-122267D01*
X332400Y-122933D01*
X332600Y-123733D01*
X332500Y-124534D01*
X332100Y-125200D01*
X330100Y-126533D01*
X329200Y-127467D01*
X328600Y-128800D01*
X328400Y-130000D01*
X332600D01*
G01X338500Y-122000D02*
X337700Y-122267D01*
X337100Y-122933D01*
X336700Y-123733D01*
X336400Y-124800D01*
X336300Y-126000D01*
X336400Y-127200D01*
X336700Y-128267D01*
X337100Y-129067D01*
X337700Y-129733D01*
X338500Y-130000D01*
X339300Y-129733D01*
X339900Y-129067D01*
X340300Y-128267D01*
X340600Y-127200D01*
X340700Y-126000D01*
X340600Y-124800D01*
X340300Y-123733D01*
X339900Y-122933D01*
X339300Y-122267D01*
X338500Y-122000D01*
G01X346500Y-130000D02*
Y-122000D01*
X345300Y-123600D01*
G01Y-130000D02*
X347700D01*
G01X352600Y-123333D02*
X353200Y-122533D01*
X353900Y-122133D01*
X354700Y-122000D01*
X355700Y-122267D01*
X356400Y-122933D01*
X356600Y-123733D01*
X356500Y-124534D01*
X356100Y-125200D01*
X354100Y-126533D01*
X353200Y-127467D01*
X352600Y-128800D01*
X352400Y-130000D01*
X356600D01*
G01X360700Y-130267D02*
X364300Y-122000D01*
G01X370500D02*
X369700Y-122267D01*
X369100Y-122933D01*
X368700Y-123733D01*
X368400Y-124800D01*
X368300Y-126000D01*
X368400Y-127200D01*
X368700Y-128267D01*
X369100Y-129067D01*
X369700Y-129733D01*
X370500Y-130000D01*
X371300Y-129733D01*
X371900Y-129067D01*
X372300Y-128267D01*
X372600Y-127200D01*
X372700Y-126000D01*
X372600Y-124800D01*
X372300Y-123733D01*
X371900Y-122933D01*
X371300Y-122267D01*
X370500Y-122000D01*
G01X376800Y-129067D02*
X377500Y-129733D01*
X378300Y-130000D01*
X379100Y-129733D01*
X379800Y-128934D01*
X380300Y-127733D01*
X380500Y-126533D01*
Y-125067D01*
X380300Y-123867D01*
X379800Y-122800D01*
X379200Y-122267D01*
X378500Y-122000D01*
X377700Y-122267D01*
X377100Y-122800D01*
X376700Y-123600D01*
X376500Y-124667D01*
X376700Y-125600D01*
X377200Y-126533D01*
X377800Y-127067D01*
X378500Y-127200D01*
X379300Y-126934D01*
X379900Y-126267D01*
X380500Y-125067D01*
G01X384700Y-130267D02*
X388300Y-122000D01*
G01X392600Y-123333D02*
X393200Y-122533D01*
X393900Y-122133D01*
X394700Y-122000D01*
X395700Y-122267D01*
X396400Y-122933D01*
X396600Y-123733D01*
X396500Y-124534D01*
X396100Y-125200D01*
X394100Y-126533D01*
X393200Y-127467D01*
X392600Y-128800D01*
X392400Y-130000D01*
X396600D01*
G01X402500D02*
X403200Y-129867D01*
X404000Y-129467D01*
X404500Y-128800D01*
X404700Y-127867D01*
X404500Y-126934D01*
X403900Y-126133D01*
X403000Y-125733D01*
X402000D01*
X401400Y-125467D01*
X400900Y-124800D01*
X400700Y-123867D01*
X401000Y-122933D01*
X401700Y-122267D01*
X402500Y-122000D01*
X403300Y-122267D01*
X404000Y-122933D01*
X404300Y-123867D01*
X404100Y-124800D01*
X403600Y-125467D01*
X403000Y-125733D01*
X402000D01*
X401100Y-126133D01*
X400500Y-126934D01*
X400300Y-127867D01*
X400500Y-128800D01*
X401000Y-129467D01*
X401800Y-129867D01*
X402500Y-130000D01*
G01X328300Y-105000D02*
Y-97000D01*
X330300D01*
X331100Y-97400D01*
X331700Y-97933D01*
X332200Y-98733D01*
X332600Y-99667D01*
X332700Y-101000D01*
X332600Y-102333D01*
X332200Y-103267D01*
X331700Y-104067D01*
X331100Y-104600D01*
X330300Y-105000D01*
X328300D01*
G01X336000D02*
X338500Y-97000D01*
X341000Y-105000D01*
G01X340100Y-102200D02*
X336900D01*
G01X346500Y-97000D02*
X345700Y-97267D01*
X345100Y-97933D01*
X344700Y-98733D01*
X344400Y-99800D01*
X344300Y-101000D01*
X344400Y-102200D01*
X344700Y-103267D01*
X345100Y-104067D01*
X345700Y-104733D01*
X346500Y-105000D01*
X347300Y-104733D01*
X347900Y-104067D01*
X348300Y-103267D01*
X348600Y-102200D01*
X348700Y-101000D01*
X348600Y-99800D01*
X348300Y-98733D01*
X347900Y-97933D01*
X347300Y-97267D01*
X346500Y-97000D01*
G01X354500D02*
Y-105000D01*
G01X352200Y-97000D02*
X356800D01*
G01X360600Y-101667D02*
X361300Y-100733D01*
X361900Y-100200D01*
X362700Y-99933D01*
X363400Y-100200D01*
X363900Y-100733D01*
X364300Y-101533D01*
X364400Y-102467D01*
X364300Y-103267D01*
X363900Y-104067D01*
X363300Y-104733D01*
X362600Y-105000D01*
X361800Y-104733D01*
X361100Y-103934D01*
X360700Y-102733D01*
X360600Y-101400D01*
X360800Y-99667D01*
X361100Y-98733D01*
X361600Y-97800D01*
X362300Y-97133D01*
X363000Y-97000D01*
X363700Y-97267D01*
X364200Y-97933D01*
G01X367900Y-105000D02*
Y-97000D01*
X370500Y-103667D01*
X373100Y-97000D01*
Y-105000D01*
G01X378500Y-97000D02*
Y-105000D01*
G01X376200Y-97000D02*
X380800D01*
G01X387300Y-100733D02*
X387700Y-100333D01*
X388000Y-99667D01*
X388200Y-98733D01*
X388000Y-97933D01*
X387600Y-97400D01*
X386900Y-97000D01*
X384200D01*
Y-105000D01*
X387500D01*
X388200Y-104467D01*
X388600Y-103667D01*
X388800Y-102733D01*
X388600Y-101800D01*
X388000Y-101000D01*
X387300Y-100733D01*
X384200D01*
G01X394500Y-105000D02*
X395200Y-104867D01*
X396000Y-104467D01*
X396500Y-103800D01*
X396700Y-102867D01*
X396500Y-101934D01*
X395900Y-101133D01*
X395000Y-100733D01*
X394000D01*
X393400Y-100467D01*
X392900Y-99800D01*
X392700Y-98867D01*
X393000Y-97933D01*
X393700Y-97267D01*
X394500Y-97000D01*
X395300Y-97267D01*
X396000Y-97933D01*
X396300Y-98867D01*
X396100Y-99800D01*
X395600Y-100467D01*
X395000Y-100733D01*
X394000D01*
X393100Y-101133D01*
X392500Y-101934D01*
X392300Y-102867D01*
X392500Y-103800D01*
X393000Y-104467D01*
X393800Y-104867D01*
X394500Y-105000D01*
G01X400300D02*
Y-97000D01*
X402300D01*
X403100Y-97400D01*
X403700Y-97933D01*
X404200Y-98733D01*
X404600Y-99667D01*
X404700Y-101000D01*
X404600Y-102333D01*
X404200Y-103267D01*
X403700Y-104067D01*
X403100Y-104600D01*
X402300Y-105000D01*
X400300D01*
G01X410500Y-97000D02*
X409700Y-97267D01*
X409100Y-97933D01*
X408700Y-98733D01*
X408400Y-99800D01*
X408300Y-101000D01*
X408400Y-102200D01*
X408700Y-103267D01*
X409100Y-104067D01*
X409700Y-104733D01*
X410500Y-105000D01*
X411300Y-104733D01*
X411900Y-104067D01*
X412300Y-103267D01*
X412600Y-102200D01*
X412700Y-101000D01*
X412600Y-99800D01*
X412300Y-98733D01*
X411900Y-97933D01*
X411300Y-97267D01*
X410500Y-97000D01*
G01X350500Y-72000D02*
Y-80000D01*
G01X348200Y-72000D02*
X352800D01*
G01X356600Y-76667D02*
X357300Y-75733D01*
X357900Y-75200D01*
X358700Y-74933D01*
X359400Y-75200D01*
X359900Y-75733D01*
X360300Y-76533D01*
X360400Y-77467D01*
X360300Y-78267D01*
X359900Y-79067D01*
X359300Y-79733D01*
X358600Y-80000D01*
X357800Y-79733D01*
X357100Y-78934D01*
X356700Y-77733D01*
X356600Y-76400D01*
X356800Y-74667D01*
X357100Y-73733D01*
X357600Y-72800D01*
X358300Y-72133D01*
X359000Y-72000D01*
X359700Y-72267D01*
X360200Y-72933D01*
G01X363900Y-80000D02*
Y-72000D01*
X366500Y-78667D01*
X369100Y-72000D01*
Y-80000D01*
G01X371500Y-82667D02*
X377500D01*
G01X380500Y-80000D02*
Y-72000D01*
X382900D01*
X383700Y-72400D01*
X384300Y-73333D01*
X384500Y-74400D01*
X384300Y-75467D01*
X383800Y-76267D01*
X382900Y-76667D01*
X380500D01*
G01X388300Y-80000D02*
Y-72000D01*
X390300D01*
X391100Y-72400D01*
X391700Y-72933D01*
X392200Y-73733D01*
X392600Y-74667D01*
X392700Y-76000D01*
X392600Y-77333D01*
X392200Y-78267D01*
X391700Y-79067D01*
X391100Y-79600D01*
X390300Y-80000D01*
X388300D01*
G01X399300Y-75733D02*
X399700Y-75333D01*
X400000Y-74667D01*
X400200Y-73733D01*
X400000Y-72933D01*
X399600Y-72400D01*
X398900Y-72000D01*
X396200D01*
Y-80000D01*
X399500D01*
X400200Y-79467D01*
X400600Y-78667D01*
X400800Y-77733D01*
X400600Y-76800D01*
X400000Y-76000D01*
X399300Y-75733D01*
X396200D01*
G01X403500Y-82667D02*
X409500D01*
G01X412300Y-80000D02*
Y-72000D01*
X414300D01*
X415100Y-72400D01*
X415700Y-72933D01*
X416200Y-73733D01*
X416600Y-74667D01*
X416700Y-76000D01*
X416600Y-77333D01*
X416200Y-78267D01*
X415700Y-79067D01*
X415100Y-79600D01*
X414300Y-80000D01*
X412300D01*
G01X419500Y-82667D02*
X425500D01*
G01X431300Y-75733D02*
X431700Y-75333D01*
X432000Y-74667D01*
X432200Y-73733D01*
X432000Y-72933D01*
X431600Y-72400D01*
X430900Y-72000D01*
X428200D01*
Y-80000D01*
X431500D01*
X432200Y-79467D01*
X432600Y-78667D01*
X432800Y-77733D01*
X432600Y-76800D01*
X432000Y-76000D01*
X431300Y-75733D01*
X428200D01*
G01X436300Y-80000D02*
Y-72000D01*
X438300D01*
X439100Y-72400D01*
X439700Y-72933D01*
X440200Y-73733D01*
X440600Y-74667D01*
X440700Y-76000D01*
X440600Y-77333D01*
X440200Y-78267D01*
X439700Y-79067D01*
X439100Y-79600D01*
X438300Y-80000D01*
X436300D01*
G01X443300Y-130000D02*
Y-122000D01*
X445300D01*
X446100Y-122400D01*
X446700Y-122933D01*
X447200Y-123733D01*
X447600Y-124667D01*
X447700Y-126000D01*
X447600Y-127333D01*
X447200Y-128267D01*
X446700Y-129067D01*
X446100Y-129600D01*
X445300Y-130000D01*
X443300D01*
G01X473000D02*
Y-122000D01*
X471800Y-123600D01*
G01Y-130000D02*
X474200D01*
G01X478800Y-128800D02*
X479400Y-129467D01*
X480100Y-129867D01*
X481000Y-130000D01*
X481900Y-129733D01*
X482600Y-129200D01*
X483100Y-128267D01*
X483200Y-127200D01*
X483000Y-126133D01*
X482500Y-125467D01*
X481800Y-124933D01*
X481100Y-124800D01*
X480400Y-124933D01*
X479500Y-125467D01*
X479800Y-122000D01*
X482500D01*
G54D32*
X119920Y328071D03*
Y676102D03*
Y1024134D03*
Y1372165D03*
Y1720197D03*
Y2068228D03*
G54D23*
X18995Y1612992D03*
X53995Y518701D03*
G54D14*
X18995Y508701D03*
X23995Y518701D03*
X21495Y559882D03*
X11692D03*
X21495Y1571811D03*
X11692D03*
X23995Y1622992D03*
X28995Y508701D03*
X38995D03*
X48995D03*
X33995Y518701D03*
X43995D03*
X51495Y559882D03*
Y1571811D03*
X43995Y1622992D03*
X33995D03*
X48995Y1612992D03*
X38995D03*
X28995D03*
X61298Y559882D03*
Y1571811D03*
X53995Y1622992D03*
G54D15*
X13995Y543701D03*
Y1587992D03*
X58995Y543701D03*
Y1587992D03*
G54D33*
X163385Y27205D03*
Y202205D03*
Y377205D03*
X163386Y552205D03*
Y727205D03*
X163385Y902205D03*
Y1077205D03*
Y1252205D03*
Y1427205D03*
Y1602205D03*
Y1777205D03*
Y1952205D03*
X373385Y32520D03*
Y207520D03*
Y382520D03*
X373386Y557520D03*
Y732520D03*
X373385Y907520D03*
Y1082520D03*
Y1257520D03*
Y1432520D03*
Y1607520D03*
Y1782520D03*
Y1957520D03*
G54D24*
X23402Y1668874D03*
Y1685410D03*
Y1701945D03*
Y1718480D03*
Y1735016D03*
Y1751551D03*
Y1768087D03*
Y1784622D03*
Y1817693D03*
Y1801158D03*
X45056Y1668874D03*
Y1685410D03*
Y1701945D03*
Y1718480D03*
Y1735016D03*
Y1751551D03*
Y1768087D03*
Y1784622D03*
Y1801158D03*
G54D25*
Y1817693D03*
G54D34*
X173385Y32520D03*
Y207520D03*
Y382520D03*
X173386Y557520D03*
Y732520D03*
X173385Y907520D03*
Y1082520D03*
Y1257520D03*
Y1432520D03*
Y1607520D03*
Y1782520D03*
Y1957520D03*
G54D16*
X5491Y528544D03*
Y1603149D03*
X67499Y528544D03*
Y1603149D03*
G54D17*
X11677Y572812D03*
Y575962D03*
X16484Y1555159D03*
Y1558309D03*
X11085Y1555291D03*
Y1558441D03*
X58750Y577016D03*
Y573866D03*
X63820Y577082D03*
Y573932D03*
X58752Y1302746D03*
Y1299596D03*
X71909Y1302580D03*
Y1299430D03*
X50331Y1302680D03*
Y1299530D03*
X54543Y1302681D03*
Y1299531D03*
X63061Y1302746D03*
Y1299596D03*
X67568Y1302581D03*
Y1299431D03*
X52958Y1336081D03*
Y1339231D03*
X107268Y78205D03*
X107263Y75055D03*
Y78205D03*
X107268Y81355D03*
X107668Y429254D03*
Y426104D03*
Y422954D03*
Y426104D03*
X107615Y777299D03*
Y774149D03*
X107617Y771001D03*
Y774151D03*
X108819Y1119015D03*
X108816Y1125313D03*
Y1122163D03*
X108819Y1122165D03*
X108573Y1473357D03*
Y1470207D03*
X108574Y1467057D03*
Y1470207D03*
X108819Y1818228D03*
Y1815078D03*
Y1818228D03*
Y1821378D03*
X155370Y91281D03*
Y88131D03*
X155366Y85017D03*
Y88167D03*
X156321Y418198D03*
Y415048D03*
X161256Y418195D03*
Y415045D03*
X155351Y439268D03*
Y436118D03*
X155348Y432969D03*
Y436119D03*
X155356Y780982D03*
X155362Y787280D03*
Y784130D03*
X155356Y784132D03*
X156117Y1116127D03*
Y1112977D03*
X160870Y1116135D03*
Y1112985D03*
X155264Y1135344D03*
Y1132194D03*
X155263Y1129045D03*
Y1132195D03*
X155834Y1480274D03*
X155816Y1477124D03*
Y1480274D03*
X155834Y1483424D03*
X155570Y1831380D03*
Y1828230D03*
X155561Y1825087D03*
Y1828237D03*
X283086Y166264D03*
Y169414D03*
X287420Y166264D03*
Y169414D03*
X276617Y238439D03*
Y235289D03*
X281193Y238439D03*
Y235289D03*
X281074Y341517D03*
Y344667D03*
X289895Y341517D03*
Y344667D03*
X285513Y341517D03*
Y344667D03*
X291002Y414015D03*
Y410865D03*
X286665Y414015D03*
Y410865D03*
X278405Y515919D03*
Y519069D03*
X273938Y515919D03*
Y519069D03*
X282776Y515919D03*
Y519069D03*
X269516Y515919D03*
Y519069D03*
X290984Y585487D03*
Y588637D03*
X283340Y691124D03*
Y694274D03*
X278955Y691124D03*
Y694274D03*
X274514Y691124D03*
Y694274D03*
X270109Y691124D03*
Y694274D03*
X278184Y763711D03*
Y760561D03*
X282737Y763711D03*
Y760561D03*
X285788Y866243D03*
Y869393D03*
X281305Y866243D03*
Y869393D03*
X276686Y866243D03*
Y869393D03*
X272181Y866243D03*
Y869393D03*
X281194Y937436D03*
Y934286D03*
X285874Y937436D03*
Y934286D03*
X290107Y1034882D03*
Y1038032D03*
X285666Y1034882D03*
Y1038032D03*
X281124Y1034882D03*
Y1038032D03*
X288188Y1112426D03*
Y1109276D03*
X284194Y1210314D03*
Y1213464D03*
X289082Y1210314D03*
Y1213464D03*
X279559Y1210314D03*
Y1213464D03*
X289210Y1287097D03*
Y1283947D03*
X284240Y1393342D03*
Y1396492D03*
X279518Y1393341D03*
Y1396491D03*
X275052Y1393341D03*
Y1396491D03*
X270579Y1393341D03*
Y1396491D03*
X275521Y1457487D03*
X279990D03*
X275521Y1460637D03*
X279990D03*
X289675Y1562451D03*
Y1565601D03*
X285054Y1562451D03*
Y1565601D03*
X289421Y1637318D03*
Y1634168D03*
X289499Y1741915D03*
Y1745065D03*
X284583Y1741915D03*
Y1745065D03*
X274704Y1741915D03*
Y1745065D03*
X279703Y1741915D03*
Y1745065D03*
X286623Y1811546D03*
Y1808396D03*
X291550Y1811546D03*
Y1808396D03*
X287121Y1916895D03*
Y1920045D03*
X282717Y1916895D03*
Y1920045D03*
X278262Y1916895D03*
Y1920045D03*
X273817Y1916895D03*
Y1920045D03*
X304151Y60393D03*
Y57243D03*
X308651Y60393D03*
Y57243D03*
X313089Y60393D03*
Y57243D03*
X299687Y60393D03*
Y57243D03*
X291943Y166264D03*
Y169414D03*
X296523Y166264D03*
Y169414D03*
X294506Y341517D03*
Y344667D03*
X295509Y585487D03*
Y588637D03*
X294617Y1034882D03*
Y1038032D03*
X292698Y1112426D03*
Y1109276D03*
X293807Y1210314D03*
Y1213464D03*
X294133Y1287097D03*
Y1283947D03*
X298870Y1562451D03*
Y1565601D03*
X294392Y1562451D03*
Y1565601D03*
X294090Y1637318D03*
Y1634168D03*
X317567Y60393D03*
Y57243D03*
X322005Y60393D03*
Y57243D03*
X320045Y1987031D03*
Y1983881D03*
X324803Y1987031D03*
Y1983881D03*
G54D35*
X173385Y21890D03*
X183385Y32520D03*
Y21890D03*
X193385Y32520D03*
Y21890D03*
X173385Y196890D03*
X183385D03*
X193385D03*
X183385Y207520D03*
X193385D03*
X173385Y371890D03*
X183385D03*
X193385D03*
X183385Y382520D03*
X193385D03*
X173386Y546890D03*
X183386Y557520D03*
Y546890D03*
X193386Y557520D03*
Y546890D03*
X173386Y721890D03*
X183386Y732520D03*
Y721890D03*
X193386Y732520D03*
Y721890D03*
X173385Y896890D03*
X183385D03*
X193385D03*
X183385Y907520D03*
X193385D03*
X173385Y1071890D03*
X183385D03*
X193385D03*
X183385Y1082520D03*
X193385D03*
X173385Y1246890D03*
X183385Y1257520D03*
Y1246890D03*
X193385Y1257520D03*
Y1246890D03*
X173385Y1421890D03*
X183385Y1432520D03*
Y1421890D03*
X193385Y1432520D03*
Y1421890D03*
X173385Y1596890D03*
X183385D03*
X193385D03*
X183385Y1607520D03*
X193385D03*
X173385Y1771890D03*
X183385D03*
X193385D03*
X183385Y1782520D03*
X193385D03*
X173385Y1946890D03*
X183385Y1957520D03*
Y1946890D03*
X193385Y1957520D03*
Y1946890D03*
X203385Y32520D03*
Y21890D03*
X213385Y32520D03*
Y21890D03*
X203385Y196890D03*
X213385D03*
X203385Y207520D03*
X213385D03*
X203385Y371890D03*
X213385D03*
X203385Y382520D03*
X213385D03*
X203386Y557520D03*
Y546890D03*
X213386Y557520D03*
Y546890D03*
X203386Y732520D03*
Y721890D03*
X213386Y732520D03*
Y721890D03*
X203385Y896890D03*
X213385D03*
X203385Y907520D03*
X213385D03*
X203385Y1071890D03*
X213385D03*
X203385Y1082520D03*
X213385D03*
X203385Y1257520D03*
Y1246890D03*
X213385Y1257520D03*
Y1246890D03*
X203385Y1432520D03*
Y1421890D03*
X213385Y1432520D03*
Y1421890D03*
X203385Y1596890D03*
X213385D03*
X203385Y1607520D03*
X213385D03*
X203385Y1771890D03*
X213385D03*
X203385Y1782520D03*
X213385D03*
X203385Y1957520D03*
Y1946890D03*
X213385Y1957520D03*
Y1946890D03*
X223385Y32520D03*
Y21890D03*
X233385Y32520D03*
Y21890D03*
X243385Y32520D03*
Y21890D03*
X223385Y196890D03*
X233385D03*
X243385D03*
X223385Y207520D03*
X233385D03*
X243385D03*
X223385Y371890D03*
X233385D03*
X243385D03*
X223385Y382520D03*
X233385D03*
X243385D03*
X223386Y557520D03*
Y546890D03*
X233386Y557520D03*
Y546890D03*
X243386Y557520D03*
Y546890D03*
X223386Y732520D03*
Y721890D03*
X233386Y732520D03*
Y721890D03*
X243386Y732520D03*
Y721890D03*
X223385Y896890D03*
X233385D03*
X243385D03*
X223385Y907520D03*
X233385D03*
X243385D03*
X223385Y1071890D03*
X233385D03*
X243385D03*
X223385Y1082520D03*
X233385D03*
X243385D03*
X223385Y1257520D03*
Y1246890D03*
X233385Y1257520D03*
Y1246890D03*
X243385Y1257520D03*
Y1246890D03*
X223385Y1432520D03*
Y1421890D03*
X233385Y1432520D03*
Y1421890D03*
X243385Y1432520D03*
Y1421890D03*
X223385Y1596890D03*
X233385D03*
X243385D03*
X223385Y1607520D03*
X233385D03*
X243385D03*
X223385Y1771890D03*
X233385D03*
X243385D03*
X223385Y1782520D03*
X233385D03*
X243385D03*
X223385Y1957520D03*
Y1946890D03*
X233385Y1957520D03*
Y1946890D03*
X243385Y1957520D03*
Y1946890D03*
X253385Y21890D03*
Y32520D03*
X263385Y21890D03*
Y32520D03*
X253385Y196890D03*
X263385D03*
X253385Y207520D03*
X263385D03*
X253385Y371890D03*
X263385D03*
X253385Y382520D03*
X263385D03*
X253386Y546890D03*
Y557520D03*
X263386Y546890D03*
Y557520D03*
X253386Y721890D03*
Y732520D03*
X263386Y721890D03*
Y732520D03*
X253385Y896890D03*
X263385D03*
X253385Y907520D03*
X263385D03*
X253385Y1071890D03*
X263385D03*
X253385Y1082520D03*
X263385D03*
X253385Y1246890D03*
Y1257520D03*
X263385Y1246890D03*
Y1257520D03*
X253385Y1421890D03*
Y1432520D03*
X263385Y1421890D03*
Y1432520D03*
X253385Y1596890D03*
X263385D03*
X253385Y1607520D03*
X263385D03*
X253385Y1771890D03*
X263385D03*
X253385Y1782520D03*
X263385D03*
X253385Y1946890D03*
Y1957520D03*
X263385Y1946890D03*
Y1957520D03*
X273385Y21890D03*
Y32520D03*
X283385Y21890D03*
Y32520D03*
X273385Y196890D03*
X283385D03*
X273385Y207520D03*
X283385D03*
X273385Y371890D03*
X283385D03*
X273385Y382520D03*
X283385D03*
X273386Y546890D03*
Y557520D03*
X283386Y546890D03*
Y557520D03*
X273386Y721890D03*
Y732520D03*
X283386Y721890D03*
Y732520D03*
X273385Y896890D03*
X283385D03*
X273385Y907520D03*
X283385D03*
X273385Y1071890D03*
X283385D03*
X273385Y1082520D03*
X283385D03*
X273385Y1246890D03*
Y1257520D03*
X283385Y1246890D03*
Y1257520D03*
X273385Y1421890D03*
Y1432520D03*
X283385Y1421890D03*
Y1432520D03*
X273385Y1596890D03*
X283385D03*
X273385Y1607520D03*
X283385D03*
X273385Y1771890D03*
X283385D03*
X273385Y1782520D03*
X283385D03*
X273385Y1946890D03*
Y1957520D03*
X283385Y1946890D03*
Y1957520D03*
X293385Y21890D03*
Y32520D03*
X303385Y21890D03*
Y32520D03*
X313385D03*
Y21890D03*
X293385Y196890D03*
X303385D03*
X313385D03*
X293385Y207520D03*
X303385D03*
X313385D03*
X293385Y371890D03*
X303385D03*
X313385D03*
X293385Y382520D03*
X303385D03*
X313385D03*
X293386Y546890D03*
Y557520D03*
X303386Y546890D03*
Y557520D03*
X313386D03*
Y546890D03*
X293386Y721890D03*
Y732520D03*
X303386Y721890D03*
Y732520D03*
X313386D03*
Y721890D03*
X293385Y896890D03*
X303385D03*
X313385D03*
X293385Y907520D03*
X303385D03*
X313385D03*
X293385Y1071890D03*
X303385D03*
X313385D03*
X293385Y1082520D03*
X303385D03*
X313385D03*
X293385Y1246890D03*
Y1257520D03*
X303385Y1246890D03*
Y1257520D03*
X313385D03*
Y1246890D03*
X293385Y1421890D03*
Y1432520D03*
X303385Y1421890D03*
Y1432520D03*
X313385D03*
Y1421890D03*
X293385Y1596890D03*
X303385D03*
X313385D03*
X293385Y1607520D03*
X303385D03*
X313385D03*
X293385Y1771890D03*
X303385D03*
X313385D03*
X293385Y1782520D03*
X303385D03*
X313385D03*
X293385Y1946890D03*
Y1957520D03*
X303385Y1946890D03*
Y1957520D03*
X313385D03*
Y1946890D03*
X337165Y24705D03*
X323385Y32520D03*
Y21890D03*
X337165Y34705D03*
Y199705D03*
X323385Y196890D03*
X337165Y209705D03*
X323385Y207520D03*
Y371890D03*
X337165Y374705D03*
Y384705D03*
X323385Y382520D03*
X337166Y549705D03*
Y559705D03*
X323386Y557520D03*
Y546890D03*
X337166Y724705D03*
X323386Y732520D03*
Y721890D03*
X337166Y734705D03*
X337165Y899705D03*
X323385Y896890D03*
X337165Y909705D03*
X323385Y907520D03*
Y1071890D03*
X337165Y1074705D03*
Y1084705D03*
X323385Y1082520D03*
X337165Y1249705D03*
Y1259705D03*
X323385Y1257520D03*
Y1246890D03*
X337165Y1424705D03*
Y1434705D03*
X323385Y1432520D03*
Y1421890D03*
X337165Y1599705D03*
X323385Y1596890D03*
X337165Y1609705D03*
X323385Y1607520D03*
Y1771890D03*
X337165Y1774705D03*
Y1784705D03*
X323385Y1782520D03*
X337165Y1949705D03*
Y1959705D03*
X323385Y1957520D03*
Y1946890D03*
X342165Y19705D03*
Y29705D03*
X347165Y24705D03*
X352165Y19705D03*
Y29705D03*
X357165Y24705D03*
X362165Y19705D03*
Y29705D03*
X347165Y34705D03*
X357165D03*
X342165Y194705D03*
X347165Y199705D03*
X352165Y194705D03*
X357165Y199705D03*
X362165Y194705D03*
X342165Y204705D03*
X347165Y209705D03*
X352165Y204705D03*
X357165Y209705D03*
X362165Y204705D03*
X342165Y369705D03*
X352165D03*
X362165D03*
X342165Y379705D03*
X347165Y374705D03*
Y384705D03*
X352165Y379705D03*
X357165Y374705D03*
Y384705D03*
X362165Y379705D03*
X342166Y544705D03*
Y554705D03*
X347166Y549705D03*
Y559705D03*
X352166Y544705D03*
Y554705D03*
X357166Y549705D03*
Y559705D03*
X362166Y544705D03*
Y554705D03*
X342166Y719705D03*
Y729705D03*
X347166Y724705D03*
X352166Y719705D03*
Y729705D03*
X357166Y724705D03*
X362166Y719705D03*
Y729705D03*
X347166Y734705D03*
X357166D03*
X342165Y894705D03*
X347165Y899705D03*
X352165Y894705D03*
X357165Y899705D03*
X362165Y894705D03*
X342165Y904705D03*
X347165Y909705D03*
X352165Y904705D03*
X357165Y909705D03*
X362165Y904705D03*
X342165Y1069705D03*
X352165D03*
X362165D03*
X342165Y1079705D03*
X347165Y1074705D03*
Y1084705D03*
X352165Y1079705D03*
X357165Y1074705D03*
Y1084705D03*
X362165Y1079705D03*
X342165Y1244705D03*
Y1254705D03*
X347165Y1249705D03*
Y1259705D03*
X352165Y1244705D03*
Y1254705D03*
X357165Y1249705D03*
Y1259705D03*
X362165Y1244705D03*
Y1254705D03*
X342165Y1419705D03*
Y1429705D03*
X347165Y1424705D03*
Y1434705D03*
X352165Y1419705D03*
Y1429705D03*
X357165Y1424705D03*
Y1434705D03*
X362165Y1419705D03*
Y1429705D03*
X342165Y1594705D03*
X347165Y1599705D03*
X352165Y1594705D03*
X357165Y1599705D03*
X362165Y1594705D03*
X342165Y1604705D03*
X347165Y1609705D03*
X352165Y1604705D03*
X357165Y1609705D03*
X362165Y1604705D03*
X342165Y1769705D03*
X352165D03*
X362165D03*
X342165Y1779705D03*
X347165Y1774705D03*
Y1784705D03*
X352165Y1779705D03*
X357165Y1774705D03*
Y1784705D03*
X362165Y1779705D03*
X342165Y1944705D03*
Y1954705D03*
X347165Y1949705D03*
Y1959705D03*
X352165Y1944705D03*
Y1954705D03*
X357165Y1949705D03*
Y1959705D03*
X362165Y1944705D03*
Y1954705D03*
G54D26*
X65354Y101180D03*
X55511Y105117D03*
X51574Y114960D03*
X55511Y124803D03*
X65354Y128740D03*
Y451180D03*
X55511Y455117D03*
X51574Y464960D03*
X55511Y474803D03*
X65354Y478740D03*
Y801180D03*
X55511Y805117D03*
X51574Y814960D03*
X55511Y824803D03*
X65354Y828740D03*
Y1151180D03*
X55511Y1155117D03*
X51574Y1164960D03*
X55511Y1174803D03*
X65354Y1178740D03*
Y1501180D03*
X55511Y1505117D03*
X51574Y1514960D03*
X55511Y1524803D03*
X65354Y1528740D03*
Y1851180D03*
X55511Y1855117D03*
X51574Y1864960D03*
X55511Y1874803D03*
X65354Y1878740D03*
X75197Y105117D03*
Y124803D03*
X79134Y114960D03*
Y464960D03*
X75197Y455117D03*
Y474803D03*
Y805117D03*
Y824803D03*
X79134Y814960D03*
Y1164960D03*
X75197Y1155117D03*
Y1174803D03*
Y1505117D03*
Y1524803D03*
X79134Y1514960D03*
Y1864960D03*
X75197Y1855117D03*
Y1874803D03*
X307086Y113385D03*
X297243Y117322D03*
X293306Y127165D03*
X297243Y137008D03*
X307086Y140945D03*
Y463385D03*
X297243Y467322D03*
X293306Y477165D03*
X297243Y487008D03*
X307086Y490945D03*
Y813385D03*
X297243Y817322D03*
X293306Y827165D03*
X297243Y837008D03*
X307086Y840945D03*
Y1329724D03*
X297243Y1333661D03*
X293306Y1343504D03*
X297243Y1353347D03*
X307086Y1357284D03*
Y1679724D03*
X297243Y1683661D03*
X293306Y1693504D03*
X297243Y1703347D03*
X307086Y1707284D03*
X307087Y2029723D03*
X297244Y2033660D03*
X293307Y2043503D03*
X297244Y2053346D03*
X307087Y2057283D03*
X320866Y127165D03*
X316929Y117322D03*
Y137008D03*
Y467322D03*
Y487008D03*
X320866Y477165D03*
Y827165D03*
X316929Y817322D03*
Y837008D03*
Y1333661D03*
Y1353347D03*
X320866Y1343504D03*
Y1693504D03*
X316929Y1683661D03*
Y1703347D03*
X316930Y2033660D03*
Y2053346D03*
X320867Y2043503D03*
G54D27*
X65354Y114960D03*
Y464960D03*
Y814960D03*
Y1164960D03*
Y1514960D03*
Y1864960D03*
X307086Y127165D03*
Y477165D03*
Y827165D03*
Y1343504D03*
Y1693504D03*
X307087Y2043503D03*
G54D36*
X271547Y235964D03*
Y241764D03*
X281569Y411540D03*
Y417340D03*
X285348Y586162D03*
Y591962D03*
X273114Y761236D03*
Y767036D03*
X275966Y934961D03*
Y940761D03*
X282958Y1109951D03*
Y1115751D03*
X283808Y1284622D03*
Y1290422D03*
X270234Y1458162D03*
Y1463962D03*
X284086Y1634843D03*
Y1640643D03*
X281066Y1809071D03*
Y1814871D03*
X294483Y57918D03*
Y63718D03*
X314562Y1983607D03*
Y1989407D03*
G54D18*
X17480Y599901D03*
Y627264D03*
Y1471949D03*
Y1499311D03*
G54D37*
X307086Y308267D03*
G54D19*
X9606Y599901D03*
Y627264D03*
Y1471949D03*
Y1499311D03*
G54D28*
X56337Y878761D03*
X388591Y62106D03*
X385616Y1991570D03*
G54D29*
X54413Y1253378D03*
X51263D03*
X54210Y1263103D03*
X51060D03*
X54277Y1257633D03*
X51127D03*
X54582Y1279783D03*
X51432D03*
X54548Y1267290D03*
X51398D03*
X54446Y1284038D03*
X51296D03*
X54582Y1275630D03*
X51432D03*
X54481Y1271544D03*
X51331D03*
X61280Y1559138D03*
X58130D03*
X105845Y20080D03*
X108995D03*
X100778Y28320D03*
X103928D03*
X100693Y24203D03*
X103843D03*
X105845Y15847D03*
X108995D03*
X108090Y46285D03*
X104940D03*
X104932Y41803D03*
X108082D03*
X100778Y32853D03*
X103928D03*
X100778Y37438D03*
X103928D03*
X104137Y78186D03*
X107287D03*
X102727Y58250D03*
X105877D03*
X100518Y391220D03*
X103668D03*
X100518Y376580D03*
X103668D03*
X100518Y386235D03*
X103668D03*
X100518Y381386D03*
X103668D03*
X100518Y371909D03*
X103668D03*
X100518Y396024D03*
X103668D03*
X100794Y400352D03*
X103944D03*
X104518Y426104D03*
X107668D03*
X101056Y720745D03*
X104206D03*
X101056Y730398D03*
X104206D03*
X101056Y725457D03*
X104206D03*
X101056Y715937D03*
X104206D03*
X104346Y745139D03*
X101196D03*
X101056Y735248D03*
X104206D03*
X101056Y739962D03*
X104206D03*
X101520Y749481D03*
X104670D03*
X104442Y774100D03*
X107592D03*
X101189Y1067515D03*
X104339D03*
X101189Y1092036D03*
X104339D03*
X101189Y1072226D03*
X104339D03*
X101189Y1081791D03*
X104339D03*
X101189Y1076901D03*
X104339D03*
X101189Y1087095D03*
X104339D03*
X104432Y1096403D03*
X101282D03*
X105880Y1102535D03*
X109030D03*
X105684Y1122166D03*
X108834D03*
X100227Y1419492D03*
X103377D03*
X100227Y1429195D03*
X103377D03*
X100227Y1424340D03*
X103377D03*
X103443Y1447919D03*
X100293D03*
X100227Y1443743D03*
X103377D03*
X100227Y1434041D03*
X103377D03*
X100227Y1438980D03*
X103377D03*
X100019Y1453131D03*
X103169D03*
X105390Y1470205D03*
X108540D03*
X101677Y1760827D03*
X104827D03*
X101677Y1770527D03*
X104827D03*
X101677Y1765722D03*
X104827D03*
X104930Y1789947D03*
X101780D03*
X101677Y1785571D03*
X104827D03*
X101677Y1775514D03*
X104827D03*
X101677Y1780542D03*
X104827D03*
X105669Y1818228D03*
X108819D03*
X103671Y1798224D03*
X106821D03*
X159676Y56744D03*
X156526D03*
X158463Y68130D03*
X155313D03*
X155202Y72497D03*
X158352D03*
X158559Y88108D03*
X155409D03*
X158490Y407575D03*
X155340D03*
X158498Y436119D03*
X155348D03*
X158950Y756757D03*
X155800D03*
X158665Y764231D03*
X155515D03*
X155113Y776673D03*
X158263D03*
X158519Y784141D03*
X155369D03*
X159278Y1106853D03*
X156128D03*
X158497Y1132178D03*
X155347D03*
X160252Y1457084D03*
X157102D03*
X158976Y1480269D03*
X155826D03*
X159505Y1462651D03*
X156355D03*
X155648Y1473020D03*
X158798D03*
X158840Y1807740D03*
X155690D03*
X158563Y1815631D03*
X155413D03*
X158806Y1828225D03*
X155656D03*
X155409Y1820360D03*
X158559D03*
X184373Y937979D03*
X181223D03*
X184284Y943579D03*
X181134D03*
X184196Y962671D03*
X181046D03*
X184285Y957071D03*
X181135D03*
X184539Y973554D03*
X181389D03*
X184397Y990958D03*
X181247D03*
X184632Y979154D03*
X181482D03*
X184353Y996558D03*
X181203D03*
X184118Y1015313D03*
X180968D03*
X184115Y1009713D03*
X180965D03*
X182329Y1025022D03*
X179179D03*
X182327Y1030622D03*
X179177D03*
X264685Y128228D03*
X261535D03*
X264929Y115559D03*
X261779D03*
X264175Y823604D03*
X261025D03*
X264335Y812170D03*
X261185D03*
X272111Y463099D03*
X268961D03*
X272038Y473677D03*
X268888D03*
X288712Y1864565D03*
X285562D03*
X288794Y1858668D03*
X285644D03*
X308906Y1524401D03*
X305756D03*
X308636Y1513883D03*
X305486D03*
X320208Y1162266D03*
X317058D03*
X320264Y1172804D03*
X317114D03*
G54D38*
X307086Y1883071D03*
G54D39*
X359842Y78780D03*
Y253780D03*
Y428779D03*
Y603779D03*
Y778780D03*
Y953780D03*
Y1128779D03*
Y1303780D03*
Y1478780D03*
Y1653780D03*
Y1828779D03*
Y2003780D03*
M02*
